G04 ================== begin FILE IDENTIFICATION RECORD ==================*
G04 Layout Name:  15750-1.brd*
G04 Film Name:    BSILK*
G04 File Format:  Gerber RS274X*
G04 File Origin:  Cadence Allegro 16.5-S056*
G04 Origin Date:  Fri Dec 30 13:21:28 2016*
G04 *
G04 Layer:  VIA CLASS/FILMMASKBOTTOM*
G04 Layer:  REF DES/ASSEMBLY_BOTTOM*
G04 Layer:  PACKAGE GEOMETRY/SILKSCREEN_BOTTOM*
G04 Layer:  DRAWING FORMAT/LAYER_PCB_STORY*
G04 Layer:  DRAWING FORMAT/LAYER_SILK_B*
G04 Layer:  BOARD GEOMETRY/SILKSCREEN_BOTTOM*
G04 *
G04 Offset:    (0.00 0.00)*
G04 Mirror:    No*
G04 Mode:      Positive*
G04 Rotation:  0*
G04 FullContactRelief:  No*
G04 UndefLineWidth:     6.00*
G04 ================== end FILE IDENTIFICATION RECORD ====================*
%FSLAX35Y35*MOIN*%
%IR0*IPPOS*OFA0.00000B0.00000*MIA0B0*SFA1.00000B1.00000*%
%ADD10C,.026*%
%ADD11C,.02*%
%ADD12C,.012*%
%ADD13C,.013*%
%ADD14C,.015*%
%ADD15C,.005*%
%ADD16C,.006*%
%ADD17C,.008*%
G75*
%LPD*%
G75*
G54D10*
X71500Y315689D03*
X67900D03*
X75100D03*
X185811Y310500D03*
X181811D03*
Y318500D03*
X185811Y314500D03*
Y326500D03*
Y322500D03*
Y318500D03*
X181811Y326500D03*
Y322500D03*
Y314500D03*
X189811Y310500D03*
Y318500D03*
Y322500D03*
Y326500D03*
Y314500D03*
G54D11*
G01X-176139Y-183003D02*
G02I-12000J0D01*
G01X-181289D02*
G02I-6850J0D01*
G01X-172139D02*
X-204139D01*
G01X-188139Y-199003D02*
Y-167003D01*
G01X-172139Y-199003D02*
Y-279003D01*
G01D02*
X1178561D01*
G01X-172139Y-234503D02*
X1178561D01*
G01X-172139Y-199003D02*
X1178561D01*
G01X92500Y361000D02*
Y347500D01*
X180000D01*
Y332000D01*
G01X153311Y309500D02*
X158311D01*
G01X267000Y359500D02*
Y326500D01*
X194500D01*
G01X238500Y73500D02*
Y68500D01*
G01Y141000D02*
Y136000D01*
G01Y182000D02*
Y177000D01*
G01Y249500D02*
Y244500D01*
G01X391061Y-199003D02*
Y-279003D01*
G01X528561Y-199003D02*
Y-279003D01*
G01X643561Y-199003D02*
Y-279003D01*
G01X811061Y-199003D02*
Y-279003D01*
G01X981061Y-199003D02*
Y-279003D01*
G01X1178561Y-199003D02*
Y-279003D01*
G01X1210561Y-183003D02*
X1178561D01*
G01X1206561D02*
G02I-12000J0D01*
G01X1201411D02*
G02I-6850J0D01*
G01X1194561Y-199003D02*
Y-167003D01*
G54D12*
G01X13591Y-105354D02*
X38787D01*
G01X13591Y363425D02*
X38787D01*
G01X262196Y-105354D02*
X237000D01*
G01Y363425D02*
X262196D01*
G01X349409Y-20709D02*
Y-51418D01*
G01Y309489D02*
Y278780D01*
G01X373031Y-20709D02*
Y-51418D01*
G01X411819Y258071D02*
X386622D01*
G01X411819Y265945D02*
X386622D01*
G01X373031Y309489D02*
Y278780D01*
G01X485441Y-105354D02*
X460244D01*
G01Y363425D02*
X485441D01*
G01X506495Y116437D02*
Y141634D01*
G01X560333Y-7874D02*
X535137D01*
G01Y265945D02*
X560333D01*
G01X588976Y116437D02*
Y141634D01*
G01X708848Y-105354D02*
X683652D01*
G01Y-7874D02*
X708848D01*
G01X683652Y0D02*
X708848D01*
G01X683652Y363425D02*
X708848D01*
G54D13*
G01X270900Y166100D02*
X268050D01*
Y163400D01*
G54D14*
G01X13592Y258071D02*
X38788D01*
G01X13592Y265945D02*
X38788D01*
G01X133465Y141634D02*
Y116437D01*
G01X133470Y141630D02*
Y116433D01*
G01X187303Y-7874D02*
X162107D01*
G01Y265945D02*
X187303D01*
G01X187308Y265941D02*
X162112D01*
G01X215946Y141634D02*
Y116437D01*
G01X215951Y116433D02*
Y141630D01*
G01X310622Y-7874D02*
X335818D01*
G01X310622Y0D02*
X335818D01*
G54D15*
G01X88500Y279167D02*
X91000D01*
Y280208D01*
X90875Y280542D01*
X90708Y280750D01*
X90375Y280833D01*
X90042Y280750D01*
X89833Y280500D01*
X89708Y280208D01*
Y279167D01*
G01Y280208D02*
X88500Y280833D01*
G01X89000Y282083D02*
X88708Y282333D01*
X88542Y282667D01*
X88500Y283042D01*
X88542Y283375D01*
X88750Y283708D01*
X89000Y283917D01*
X89250Y283958D01*
X89542Y283875D01*
X89750Y283583D01*
X89833Y283292D01*
Y282917D01*
G01Y283292D02*
X89958Y283542D01*
X90167Y283750D01*
X90417Y283833D01*
X90667Y283750D01*
X90875Y283542D01*
X91000Y283167D01*
X90958Y282792D01*
X90792Y282417D01*
G01X89542Y285208D02*
X89833Y285500D01*
X90000Y285750D01*
X90083Y286083D01*
X90000Y286375D01*
X89833Y286583D01*
X89583Y286750D01*
X89292Y286792D01*
X89042Y286750D01*
X88792Y286583D01*
X88583Y286333D01*
X88500Y286042D01*
X88583Y285708D01*
X88833Y285417D01*
X89208Y285250D01*
X89625Y285208D01*
X90167Y285292D01*
X90458Y285417D01*
X90750Y285625D01*
X90958Y285917D01*
X91000Y286208D01*
X90917Y286500D01*
X90708Y286708D01*
G01X84000Y279167D02*
X86500D01*
Y280208D01*
X86375Y280542D01*
X86208Y280750D01*
X85875Y280833D01*
X85542Y280750D01*
X85333Y280500D01*
X85208Y280208D01*
Y279167D01*
G01Y280208D02*
X84000Y280833D01*
G01X84500Y282083D02*
X84208Y282333D01*
X84042Y282667D01*
X84000Y283042D01*
X84042Y283375D01*
X84250Y283708D01*
X84500Y283917D01*
X84750Y283958D01*
X85042Y283875D01*
X85250Y283583D01*
X85333Y283292D01*
Y282917D01*
G01Y283292D02*
X85458Y283542D01*
X85667Y283750D01*
X85917Y283833D01*
X86167Y283750D01*
X86375Y283542D01*
X86500Y283167D01*
X86458Y282792D01*
X86292Y282417D01*
G01X84375Y285083D02*
X84167Y285333D01*
X84042Y285625D01*
X84000Y286000D01*
X84083Y286375D01*
X84250Y286667D01*
X84542Y286875D01*
X84875Y286917D01*
X85208Y286833D01*
X85417Y286625D01*
X85583Y286333D01*
X85625Y286042D01*
X85583Y285750D01*
X85417Y285375D01*
X86500Y285500D01*
Y286625D01*
G01X82500Y300167D02*
X85000D01*
Y301208D01*
X84875Y301542D01*
X84708Y301750D01*
X84375Y301833D01*
X84042Y301750D01*
X83833Y301500D01*
X83708Y301208D01*
Y300167D01*
G01Y301208D02*
X82500Y301833D01*
G01X83542Y303208D02*
X83833Y303500D01*
X84000Y303750D01*
X84083Y304083D01*
X84000Y304375D01*
X83833Y304583D01*
X83583Y304750D01*
X83292Y304792D01*
X83042Y304750D01*
X82792Y304583D01*
X82583Y304333D01*
X82500Y304042D01*
X82583Y303708D01*
X82833Y303417D01*
X83208Y303250D01*
X83625Y303208D01*
X84167Y303292D01*
X84458Y303417D01*
X84750Y303625D01*
X84958Y303917D01*
X85000Y304208D01*
X84917Y304500D01*
X84708Y304708D01*
G01X82500Y307500D02*
X85000D01*
X83208Y305958D01*
Y308042D01*
G01X78500Y300167D02*
X81000D01*
Y301208D01*
X80875Y301542D01*
X80708Y301750D01*
X80375Y301833D01*
X80042Y301750D01*
X79833Y301500D01*
X79708Y301208D01*
Y300167D01*
G01Y301208D02*
X78500Y301833D01*
G01X79542Y303208D02*
X79833Y303500D01*
X80000Y303750D01*
X80083Y304083D01*
X80000Y304375D01*
X79833Y304583D01*
X79583Y304750D01*
X79292Y304792D01*
X79042Y304750D01*
X78792Y304583D01*
X78583Y304333D01*
X78500Y304042D01*
X78583Y303708D01*
X78833Y303417D01*
X79208Y303250D01*
X79625Y303208D01*
X80167Y303292D01*
X80458Y303417D01*
X80750Y303625D01*
X80958Y303917D01*
X81000Y304208D01*
X80917Y304500D01*
X80708Y304708D01*
G01X79000Y306083D02*
X78708Y306333D01*
X78542Y306667D01*
X78500Y307042D01*
X78542Y307375D01*
X78750Y307708D01*
X79000Y307917D01*
X79250Y307958D01*
X79542Y307875D01*
X79750Y307583D01*
X79833Y307292D01*
Y306917D01*
G01Y307292D02*
X79958Y307542D01*
X80167Y307750D01*
X80417Y307833D01*
X80667Y307750D01*
X80875Y307542D01*
X81000Y307167D01*
X80958Y306792D01*
X80792Y306417D01*
G01X86500Y300167D02*
X89000D01*
Y301208D01*
X88875Y301542D01*
X88708Y301750D01*
X88375Y301833D01*
X88042Y301750D01*
X87833Y301500D01*
X87708Y301208D01*
Y300167D01*
G01Y301208D02*
X86500Y301833D01*
G01X87542Y303208D02*
X87833Y303500D01*
X88000Y303750D01*
X88083Y304083D01*
X88000Y304375D01*
X87833Y304583D01*
X87583Y304750D01*
X87292Y304792D01*
X87042Y304750D01*
X86792Y304583D01*
X86583Y304333D01*
X86500Y304042D01*
X86583Y303708D01*
X86833Y303417D01*
X87208Y303250D01*
X87625Y303208D01*
X88167Y303292D01*
X88458Y303417D01*
X88750Y303625D01*
X88958Y303917D01*
X89000Y304208D01*
X88917Y304500D01*
X88708Y304708D01*
G01X88583Y306208D02*
X88833Y306458D01*
X88958Y306750D01*
X89000Y307083D01*
X88917Y307500D01*
X88708Y307792D01*
X88458Y307875D01*
X88208Y307833D01*
X88000Y307667D01*
X87583Y306833D01*
X87292Y306458D01*
X86875Y306208D01*
X86500Y306125D01*
Y307875D01*
G01X74500Y300167D02*
X77000D01*
Y301208D01*
X76875Y301542D01*
X76708Y301750D01*
X76375Y301833D01*
X76042Y301750D01*
X75833Y301500D01*
X75708Y301208D01*
Y300167D01*
G01Y301208D02*
X74500Y301833D01*
G01X75542Y303208D02*
X75833Y303500D01*
X76000Y303750D01*
X76083Y304083D01*
X76000Y304375D01*
X75833Y304583D01*
X75583Y304750D01*
X75292Y304792D01*
X75042Y304750D01*
X74792Y304583D01*
X74583Y304333D01*
X74500Y304042D01*
X74583Y303708D01*
X74833Y303417D01*
X75208Y303250D01*
X75625Y303208D01*
X76167Y303292D01*
X76458Y303417D01*
X76750Y303625D01*
X76958Y303917D01*
X77000Y304208D01*
X76917Y304500D01*
X76708Y304708D01*
G01X74500Y307000D02*
X77000D01*
X76500Y306500D01*
G01X74500D02*
Y307500D01*
G01X92833Y315000D02*
Y317500D01*
X91792D01*
X91458Y317375D01*
X91250Y317208D01*
X91167Y316875D01*
X91250Y316542D01*
X91500Y316333D01*
X91792Y316208D01*
X92833D01*
G01X91792D02*
X91167Y315000D01*
G01X89792Y317083D02*
X89542Y317333D01*
X89250Y317458D01*
X88917Y317500D01*
X88500Y317417D01*
X88208Y317208D01*
X88125Y316958D01*
X88167Y316708D01*
X88333Y316500D01*
X89167Y316083D01*
X89542Y315792D01*
X89792Y315375D01*
X89875Y315000D01*
X88125D01*
G01X86083D02*
X86000Y315542D01*
X85875Y316000D01*
X85708Y316417D01*
X85500Y316875D01*
X85167Y317500D01*
X86833D01*
G01X92833Y320000D02*
Y322500D01*
X91792D01*
X91458Y322375D01*
X91250Y322208D01*
X91167Y321875D01*
X91250Y321542D01*
X91500Y321333D01*
X91792Y321208D01*
X92833D01*
G01X91792D02*
X91167Y320000D01*
G01X89792Y322083D02*
X89542Y322333D01*
X89250Y322458D01*
X88917Y322500D01*
X88500Y322417D01*
X88208Y322208D01*
X88125Y321958D01*
X88167Y321708D01*
X88333Y321500D01*
X89167Y321083D01*
X89542Y320792D01*
X89792Y320375D01*
X89875Y320000D01*
X88125D01*
G01X86917Y320375D02*
X86667Y320167D01*
X86375Y320042D01*
X86000Y320000D01*
X85625Y320083D01*
X85333Y320250D01*
X85125Y320542D01*
X85083Y320875D01*
X85167Y321208D01*
X85375Y321417D01*
X85667Y321583D01*
X85958Y321625D01*
X86250Y321583D01*
X86625Y321417D01*
X86500Y322500D01*
X85375D01*
G01X104000Y290667D02*
X106500D01*
Y291708D01*
X106375Y292042D01*
X106208Y292250D01*
X105875Y292333D01*
X105542Y292250D01*
X105333Y292000D01*
X105208Y291708D01*
Y290667D01*
G01Y291708D02*
X104000Y292333D01*
G01X104375Y293583D02*
X104167Y293833D01*
X104042Y294125D01*
X104000Y294500D01*
X104083Y294875D01*
X104250Y295167D01*
X104542Y295375D01*
X104875Y295417D01*
X105208Y295333D01*
X105417Y295125D01*
X105583Y294833D01*
X105625Y294542D01*
X105583Y294250D01*
X105417Y293875D01*
X106500Y294000D01*
Y295125D01*
G01X104000Y297417D02*
X104542Y297500D01*
X105000Y297625D01*
X105417Y297792D01*
X105875Y298000D01*
X106500Y298333D01*
Y296667D01*
G01X98500Y335667D02*
X101000D01*
Y336708D01*
X100875Y337042D01*
X100708Y337250D01*
X100375Y337333D01*
X100042Y337250D01*
X99833Y337000D01*
X99708Y336708D01*
Y335667D01*
G01Y336708D02*
X98500Y337333D01*
G01X99000Y338583D02*
X98708Y338833D01*
X98542Y339167D01*
X98500Y339542D01*
X98542Y339875D01*
X98750Y340208D01*
X99000Y340417D01*
X99250Y340458D01*
X99542Y340375D01*
X99750Y340083D01*
X99833Y339792D01*
Y339417D01*
G01Y339792D02*
X99958Y340042D01*
X100167Y340250D01*
X100417Y340333D01*
X100667Y340250D01*
X100875Y340042D01*
X101000Y339667D01*
X100958Y339292D01*
X100792Y338917D01*
G01X101000Y342500D02*
X100917Y342167D01*
X100708Y341917D01*
X100458Y341750D01*
X100125Y341625D01*
X99750Y341583D01*
X99375Y341625D01*
X99042Y341750D01*
X98792Y341917D01*
X98583Y342167D01*
X98500Y342500D01*
X98583Y342833D01*
X98792Y343083D01*
X99042Y343250D01*
X99375Y343375D01*
X99750Y343417D01*
X100125Y343375D01*
X100458Y343250D01*
X100708Y343083D01*
X100917Y342833D01*
X101000Y342500D01*
G01X102500Y335667D02*
X105000D01*
Y336708D01*
X104875Y337042D01*
X104708Y337250D01*
X104375Y337333D01*
X104042Y337250D01*
X103833Y337000D01*
X103708Y336708D01*
Y335667D01*
G01Y336708D02*
X102500Y337333D01*
G01X102875Y338583D02*
X102667Y338833D01*
X102542Y339125D01*
X102500Y339500D01*
X102583Y339875D01*
X102750Y340167D01*
X103042Y340375D01*
X103375Y340417D01*
X103708Y340333D01*
X103917Y340125D01*
X104083Y339833D01*
X104125Y339542D01*
X104083Y339250D01*
X103917Y338875D01*
X105000Y339000D01*
Y340125D01*
G01X102792Y341792D02*
X102583Y342083D01*
X102500Y342417D01*
X102583Y342750D01*
X102833Y343042D01*
X103208Y343250D01*
X103583Y343333D01*
X104042D01*
X104417Y343250D01*
X104750Y343042D01*
X104917Y342792D01*
X105000Y342500D01*
X104917Y342167D01*
X104750Y341917D01*
X104500Y341750D01*
X104167Y341667D01*
X103875Y341750D01*
X103583Y341958D01*
X103417Y342208D01*
X103375Y342500D01*
X103458Y342833D01*
X103667Y343083D01*
X104042Y343333D01*
G01X90500Y335667D02*
X93000D01*
Y336708D01*
X92875Y337042D01*
X92708Y337250D01*
X92375Y337333D01*
X92042Y337250D01*
X91833Y337000D01*
X91708Y336708D01*
Y335667D01*
G01Y336708D02*
X90500Y337333D01*
G01X90875Y338583D02*
X90667Y338833D01*
X90542Y339125D01*
X90500Y339500D01*
X90583Y339875D01*
X90750Y340167D01*
X91042Y340375D01*
X91375Y340417D01*
X91708Y340333D01*
X91917Y340125D01*
X92083Y339833D01*
X92125Y339542D01*
X92083Y339250D01*
X91917Y338875D01*
X93000Y339000D01*
Y340125D01*
G01X90500Y342500D02*
X93000D01*
X92500Y342000D01*
G01X90500D02*
Y343000D01*
G01X94500Y335667D02*
X97000D01*
Y336708D01*
X96875Y337042D01*
X96708Y337250D01*
X96375Y337333D01*
X96042Y337250D01*
X95833Y337000D01*
X95708Y336708D01*
Y335667D01*
G01Y336708D02*
X94500Y337333D01*
G01X94875Y338583D02*
X94667Y338833D01*
X94542Y339125D01*
X94500Y339500D01*
X94583Y339875D01*
X94750Y340167D01*
X95042Y340375D01*
X95375Y340417D01*
X95708Y340333D01*
X95917Y340125D01*
X96083Y339833D01*
X96125Y339542D01*
X96083Y339250D01*
X95917Y338875D01*
X97000Y339000D01*
Y340125D01*
G01Y342500D02*
X96917Y342167D01*
X96708Y341917D01*
X96458Y341750D01*
X96125Y341625D01*
X95750Y341583D01*
X95375Y341625D01*
X95042Y341750D01*
X94792Y341917D01*
X94583Y342167D01*
X94500Y342500D01*
X94583Y342833D01*
X94792Y343083D01*
X95042Y343250D01*
X95375Y343375D01*
X95750Y343417D01*
X96125Y343375D01*
X96458Y343250D01*
X96708Y343083D01*
X96917Y342833D01*
X97000Y342500D01*
G01X118000Y279167D02*
X120500D01*
Y280208D01*
X120375Y280542D01*
X120208Y280750D01*
X119875Y280833D01*
X119542Y280750D01*
X119333Y280500D01*
X119208Y280208D01*
Y279167D01*
G01Y280208D02*
X118000Y280833D01*
G01X120083Y282208D02*
X120333Y282458D01*
X120458Y282750D01*
X120500Y283083D01*
X120417Y283500D01*
X120208Y283792D01*
X119958Y283875D01*
X119708Y283833D01*
X119500Y283667D01*
X119083Y282833D01*
X118792Y282458D01*
X118375Y282208D01*
X118000Y282125D01*
Y283875D01*
G01X118292Y285292D02*
X118083Y285583D01*
X118000Y285917D01*
X118083Y286250D01*
X118333Y286542D01*
X118708Y286750D01*
X119083Y286833D01*
X119542D01*
X119917Y286750D01*
X120250Y286542D01*
X120417Y286292D01*
X120500Y286000D01*
X120417Y285667D01*
X120250Y285417D01*
X120000Y285250D01*
X119667Y285167D01*
X119375Y285250D01*
X119083Y285458D01*
X118917Y285708D01*
X118875Y286000D01*
X118958Y286333D01*
X119167Y286583D01*
X119542Y286833D01*
G01X122500Y279167D02*
X125000D01*
Y280208D01*
X124875Y280542D01*
X124708Y280750D01*
X124375Y280833D01*
X124042Y280750D01*
X123833Y280500D01*
X123708Y280208D01*
Y279167D01*
G01Y280208D02*
X122500Y280833D01*
G01X123000Y282083D02*
X122708Y282333D01*
X122542Y282667D01*
X122500Y283042D01*
X122542Y283375D01*
X122750Y283708D01*
X123000Y283917D01*
X123250Y283958D01*
X123542Y283875D01*
X123750Y283583D01*
X123833Y283292D01*
Y282917D01*
G01Y283292D02*
X123958Y283542D01*
X124167Y283750D01*
X124417Y283833D01*
X124667Y283750D01*
X124875Y283542D01*
X125000Y283167D01*
X124958Y282792D01*
X124792Y282417D01*
G01X122500Y286500D02*
X125000D01*
X123208Y284958D01*
Y287042D01*
G01X116333Y292000D02*
Y294500D01*
X115292D01*
X114958Y294375D01*
X114750Y294208D01*
X114667Y293875D01*
X114750Y293542D01*
X115000Y293333D01*
X115292Y293208D01*
X116333D01*
G01X115292D02*
X114667Y292000D01*
G01X113417Y292375D02*
X113167Y292167D01*
X112875Y292042D01*
X112500Y292000D01*
X112125Y292083D01*
X111833Y292250D01*
X111625Y292542D01*
X111583Y292875D01*
X111667Y293208D01*
X111875Y293417D01*
X112167Y293583D01*
X112458Y293625D01*
X112750Y293583D01*
X113125Y293417D01*
X113000Y294500D01*
X111875D01*
G01X109000Y292000D02*
Y294500D01*
X110542Y292708D01*
X108458D01*
G01X122748Y306591D02*
X125248D01*
Y307632D01*
X125123Y307966D01*
X124956Y308174D01*
X124623Y308257D01*
X124290Y308174D01*
X124081Y307924D01*
X123956Y307632D01*
Y306591D01*
G01Y307632D02*
X122748Y308257D01*
G01X123123Y309507D02*
X122915Y309757D01*
X122790Y310049D01*
X122748Y310424D01*
X122831Y310799D01*
X122998Y311091D01*
X123290Y311299D01*
X123623Y311341D01*
X123956Y311257D01*
X124165Y311049D01*
X124331Y310757D01*
X124373Y310466D01*
X124331Y310174D01*
X124165Y309799D01*
X125248Y309924D01*
Y311049D01*
G01X122748Y313424D02*
X122790Y313716D01*
X122915Y314049D01*
X123123Y314257D01*
X123415Y314341D01*
X123706Y314257D01*
X123956Y314007D01*
X124081Y313632D01*
Y313216D01*
X124165Y312966D01*
X124373Y312757D01*
X124665Y312674D01*
X124956Y312799D01*
X125165Y313091D01*
X125248Y313424D01*
X125165Y313757D01*
X124956Y314049D01*
X124665Y314174D01*
X124373Y314091D01*
X124165Y313882D01*
X124081Y313632D01*
Y313216D01*
X123956Y312841D01*
X123706Y312591D01*
X123415Y312507D01*
X123123Y312591D01*
X122915Y312799D01*
X122790Y313132D01*
X122748Y313424D01*
G01X126748Y306591D02*
X129248D01*
Y307632D01*
X129123Y307966D01*
X128956Y308174D01*
X128623Y308257D01*
X128290Y308174D01*
X128081Y307924D01*
X127956Y307632D01*
Y306591D01*
G01Y307632D02*
X126748Y308257D01*
G01X127790Y309632D02*
X128081Y309924D01*
X128248Y310174D01*
X128331Y310507D01*
X128248Y310799D01*
X128081Y311007D01*
X127831Y311174D01*
X127540Y311216D01*
X127290Y311174D01*
X127040Y311007D01*
X126831Y310757D01*
X126748Y310466D01*
X126831Y310132D01*
X127081Y309841D01*
X127456Y309674D01*
X127873Y309632D01*
X128415Y309716D01*
X128706Y309841D01*
X128998Y310049D01*
X129206Y310341D01*
X129248Y310632D01*
X129165Y310924D01*
X128956Y311132D01*
G01X129248Y313424D02*
X129165Y313091D01*
X128956Y312841D01*
X128706Y312674D01*
X128373Y312549D01*
X127998Y312507D01*
X127623Y312549D01*
X127290Y312674D01*
X127040Y312841D01*
X126831Y313091D01*
X126748Y313424D01*
X126831Y313757D01*
X127040Y314007D01*
X127290Y314174D01*
X127623Y314299D01*
X127998Y314341D01*
X128373Y314299D01*
X128706Y314174D01*
X128956Y314007D01*
X129165Y313757D01*
X129248Y313424D01*
G01X145000Y317167D02*
X147500D01*
Y318167D01*
X147375Y318500D01*
X147083Y318750D01*
X146750Y318833D01*
X146417Y318750D01*
X146167Y318542D01*
X146042Y318167D01*
Y317167D01*
G01X145000Y320167D02*
X147500D01*
Y321208D01*
X147375Y321542D01*
X147208Y321750D01*
X146875Y321833D01*
X146542Y321750D01*
X146333Y321500D01*
X146208Y321208D01*
Y320167D01*
G01Y321208D02*
X145000Y321833D01*
G01X147083Y323208D02*
X147333Y323458D01*
X147458Y323750D01*
X147500Y324083D01*
X147417Y324500D01*
X147208Y324792D01*
X146958Y324875D01*
X146708Y324833D01*
X146500Y324667D01*
X146083Y323833D01*
X145792Y323458D01*
X145375Y323208D01*
X145000Y323125D01*
Y324875D01*
G01Y327000D02*
X147500D01*
X147000Y326500D01*
G01X145000D02*
Y327500D01*
G01X154500Y317167D02*
X157000D01*
Y318167D01*
X156875Y318500D01*
X156583Y318750D01*
X156250Y318833D01*
X155917Y318750D01*
X155667Y318542D01*
X155542Y318167D01*
Y317167D01*
G01X156792Y321917D02*
X156917Y321667D01*
X157000Y321375D01*
Y321042D01*
X156875Y320667D01*
X156667Y320375D01*
X156417Y320167D01*
X156000Y320000D01*
X155625Y319958D01*
X155250Y320042D01*
X155000Y320167D01*
X154750Y320417D01*
X154583Y320708D01*
X154500Y321000D01*
Y321292D01*
X154583Y321583D01*
X154708Y321833D01*
X154875Y322042D01*
G01X155000Y323083D02*
X154708Y323333D01*
X154542Y323667D01*
X154500Y324042D01*
X154542Y324375D01*
X154750Y324708D01*
X155000Y324917D01*
X155250Y324958D01*
X155542Y324875D01*
X155750Y324583D01*
X155833Y324292D01*
Y323917D01*
G01Y324292D02*
X155958Y324542D01*
X156167Y324750D01*
X156417Y324833D01*
X156667Y324750D01*
X156875Y324542D01*
X157000Y324167D01*
X156958Y323792D01*
X156792Y323417D01*
G01X155542Y326208D02*
X155833Y326500D01*
X156000Y326750D01*
X156083Y327083D01*
X156000Y327375D01*
X155833Y327583D01*
X155583Y327750D01*
X155292Y327792D01*
X155042Y327750D01*
X154792Y327583D01*
X154583Y327333D01*
X154500Y327042D01*
X154583Y326708D01*
X154833Y326417D01*
X155208Y326250D01*
X155625Y326208D01*
X156167Y326292D01*
X156458Y326417D01*
X156750Y326625D01*
X156958Y326917D01*
X157000Y327208D01*
X156917Y327500D01*
X156708Y327708D01*
G01X166563Y283743D02*
X169063D01*
Y284743D01*
X168938Y285076D01*
X168646Y285326D01*
X168313Y285409D01*
X167980Y285326D01*
X167730Y285118D01*
X167605Y284743D01*
Y283743D01*
G01X166563Y286743D02*
X169063D01*
Y287784D01*
X168938Y288118D01*
X168771Y288326D01*
X168438Y288409D01*
X168105Y288326D01*
X167896Y288076D01*
X167771Y287784D01*
Y286743D01*
G01Y287784D02*
X166563Y288409D01*
G01X167063Y289659D02*
X166771Y289909D01*
X166605Y290243D01*
X166563Y290618D01*
X166605Y290951D01*
X166813Y291284D01*
X167063Y291493D01*
X167313Y291534D01*
X167605Y291451D01*
X167813Y291159D01*
X167896Y290868D01*
Y290493D01*
G01Y290868D02*
X168021Y291118D01*
X168230Y291326D01*
X168480Y291409D01*
X168730Y291326D01*
X168938Y291118D01*
X169063Y290743D01*
X169021Y290368D01*
X168855Y289993D01*
G01X169063Y293576D02*
X168980Y293243D01*
X168771Y292993D01*
X168521Y292826D01*
X168188Y292701D01*
X167813Y292659D01*
X167438Y292701D01*
X167105Y292826D01*
X166855Y292993D01*
X166646Y293243D01*
X166563Y293576D01*
X166646Y293909D01*
X166855Y294159D01*
X167105Y294326D01*
X167438Y294451D01*
X167813Y294493D01*
X168188Y294451D01*
X168521Y294326D01*
X168771Y294159D01*
X168980Y293909D01*
X169063Y293576D01*
G01X170563Y283743D02*
X173063D01*
Y284743D01*
X172938Y285076D01*
X172646Y285326D01*
X172313Y285409D01*
X171980Y285326D01*
X171730Y285118D01*
X171605Y284743D01*
Y283743D01*
G01X170563Y286743D02*
X173063D01*
Y287784D01*
X172938Y288118D01*
X172771Y288326D01*
X172438Y288409D01*
X172105Y288326D01*
X171896Y288076D01*
X171771Y287784D01*
Y286743D01*
G01Y287784D02*
X170563Y288409D01*
G01X171063Y289659D02*
X170771Y289909D01*
X170605Y290243D01*
X170563Y290618D01*
X170605Y290951D01*
X170813Y291284D01*
X171063Y291493D01*
X171313Y291534D01*
X171605Y291451D01*
X171813Y291159D01*
X171896Y290868D01*
Y290493D01*
G01Y290868D02*
X172021Y291118D01*
X172230Y291326D01*
X172480Y291409D01*
X172730Y291326D01*
X172938Y291118D01*
X173063Y290743D01*
X173021Y290368D01*
X172855Y289993D01*
G01X170563Y293576D02*
X173063D01*
X172563Y293076D01*
G01X170563D02*
Y294076D01*
G01X174563Y283743D02*
X177063D01*
Y284743D01*
X176938Y285076D01*
X176646Y285326D01*
X176313Y285409D01*
X175980Y285326D01*
X175730Y285118D01*
X175605Y284743D01*
Y283743D01*
G01X174563Y286743D02*
X177063D01*
Y287784D01*
X176938Y288118D01*
X176771Y288326D01*
X176438Y288409D01*
X176105Y288326D01*
X175896Y288076D01*
X175771Y287784D01*
Y286743D01*
G01Y287784D02*
X174563Y288409D01*
G01X175063Y289659D02*
X174771Y289909D01*
X174605Y290243D01*
X174563Y290618D01*
X174605Y290951D01*
X174813Y291284D01*
X175063Y291493D01*
X175313Y291534D01*
X175605Y291451D01*
X175813Y291159D01*
X175896Y290868D01*
Y290493D01*
G01Y290868D02*
X176021Y291118D01*
X176230Y291326D01*
X176480Y291409D01*
X176730Y291326D01*
X176938Y291118D01*
X177063Y290743D01*
X177021Y290368D01*
X176855Y289993D01*
G01X174938Y292659D02*
X174730Y292909D01*
X174605Y293201D01*
X174563Y293576D01*
X174646Y293951D01*
X174813Y294243D01*
X175105Y294451D01*
X175438Y294493D01*
X175771Y294409D01*
X175980Y294201D01*
X176146Y293909D01*
X176188Y293618D01*
X176146Y293326D01*
X175980Y292951D01*
X177063Y293076D01*
Y294201D01*
G01X202333Y308500D02*
Y311000D01*
X201333D01*
X201000Y310875D01*
X200750Y310583D01*
X200667Y310250D01*
X200750Y309917D01*
X200958Y309667D01*
X201333Y309542D01*
X202333D01*
G01X199333Y308500D02*
Y311000D01*
X198292D01*
X197958Y310875D01*
X197750Y310708D01*
X197667Y310375D01*
X197750Y310042D01*
X198000Y309833D01*
X198292Y309708D01*
X199333D01*
G01X198292D02*
X197667Y308500D01*
G01X196292Y310583D02*
X196042Y310833D01*
X195750Y310958D01*
X195417Y311000D01*
X195000Y310917D01*
X194708Y310708D01*
X194625Y310458D01*
X194667Y310208D01*
X194833Y310000D01*
X195667Y309583D01*
X196042Y309292D01*
X196292Y308875D01*
X196375Y308500D01*
X194625D01*
G01X193417Y308875D02*
X193167Y308667D01*
X192875Y308542D01*
X192500Y308500D01*
X192125Y308583D01*
X191833Y308750D01*
X191625Y309042D01*
X191583Y309375D01*
X191667Y309708D01*
X191875Y309917D01*
X192167Y310083D01*
X192458Y310125D01*
X192750Y310083D01*
X193125Y309917D01*
X193000Y311000D01*
X191875D01*
G01X213333Y301500D02*
Y304000D01*
X212333D01*
X212000Y303875D01*
X211750Y303583D01*
X211667Y303250D01*
X211750Y302917D01*
X211958Y302667D01*
X212333Y302542D01*
X213333D01*
G01X210333Y301500D02*
Y304000D01*
X209292D01*
X208958Y303875D01*
X208750Y303708D01*
X208667Y303375D01*
X208750Y303042D01*
X209000Y302833D01*
X209292Y302708D01*
X210333D01*
G01X209292D02*
X208667Y301500D01*
G01X207292Y303583D02*
X207042Y303833D01*
X206750Y303958D01*
X206417Y304000D01*
X206000Y303917D01*
X205708Y303708D01*
X205625Y303458D01*
X205667Y303208D01*
X205833Y303000D01*
X206667Y302583D01*
X207042Y302292D01*
X207292Y301875D01*
X207375Y301500D01*
X205625D01*
G01X203500D02*
X203208Y301542D01*
X202875Y301667D01*
X202667Y301875D01*
X202583Y302167D01*
X202667Y302458D01*
X202917Y302708D01*
X203292Y302833D01*
X203708D01*
X203958Y302917D01*
X204167Y303125D01*
X204250Y303417D01*
X204125Y303708D01*
X203833Y303917D01*
X203500Y304000D01*
X203167Y303917D01*
X202875Y303708D01*
X202750Y303417D01*
X202833Y303125D01*
X203042Y302917D01*
X203292Y302833D01*
X203708D01*
X204083Y302708D01*
X204333Y302458D01*
X204417Y302167D01*
X204333Y301875D01*
X204125Y301667D01*
X203792Y301542D01*
X203500Y301500D01*
G01X203333Y321000D02*
Y323500D01*
X202333D01*
X202000Y323375D01*
X201750Y323083D01*
X201667Y322750D01*
X201750Y322417D01*
X201958Y322167D01*
X202333Y322042D01*
X203333D01*
G01X200333Y321000D02*
Y323500D01*
X199292D01*
X198958Y323375D01*
X198750Y323208D01*
X198667Y322875D01*
X198750Y322542D01*
X199000Y322333D01*
X199292Y322208D01*
X200333D01*
G01X199292D02*
X198667Y321000D01*
G01X197417Y321500D02*
X197167Y321208D01*
X196833Y321042D01*
X196458Y321000D01*
X196125Y321042D01*
X195792Y321250D01*
X195583Y321500D01*
X195542Y321750D01*
X195625Y322042D01*
X195917Y322250D01*
X196208Y322333D01*
X196583D01*
G01X196208D02*
X195958Y322458D01*
X195750Y322667D01*
X195667Y322917D01*
X195750Y323167D01*
X195958Y323375D01*
X196333Y323500D01*
X196708Y323458D01*
X197083Y323292D01*
G01X194292Y322042D02*
X194000Y322333D01*
X193750Y322500D01*
X193417Y322583D01*
X193125Y322500D01*
X192917Y322333D01*
X192750Y322083D01*
X192708Y321792D01*
X192750Y321542D01*
X192917Y321292D01*
X193167Y321083D01*
X193458Y321000D01*
X193792Y321083D01*
X194083Y321333D01*
X194250Y321708D01*
X194292Y322125D01*
X194208Y322667D01*
X194083Y322958D01*
X193875Y323250D01*
X193583Y323458D01*
X193292Y323500D01*
X193000Y323417D01*
X192792Y323208D01*
G01X220000Y145667D02*
X222500D01*
Y146708D01*
X222375Y147042D01*
X222208Y147250D01*
X221875Y147333D01*
X221542Y147250D01*
X221333Y147000D01*
X221208Y146708D01*
Y145667D01*
G01Y146708D02*
X220000Y147333D01*
G01Y149500D02*
X222500D01*
X222000Y149000D01*
G01X220000D02*
Y150000D01*
G01X222083Y151708D02*
X222333Y151958D01*
X222458Y152250D01*
X222500Y152583D01*
X222417Y153000D01*
X222208Y153292D01*
X221958Y153375D01*
X221708Y153333D01*
X221500Y153167D01*
X221083Y152333D01*
X220792Y151958D01*
X220375Y151708D01*
X220000Y151625D01*
Y153375D01*
G01Y155167D02*
X222500D01*
Y156208D01*
X222375Y156542D01*
X222208Y156750D01*
X221875Y156833D01*
X221542Y156750D01*
X221333Y156500D01*
X221208Y156208D01*
Y155167D01*
G01Y156208D02*
X220000Y156833D01*
G01Y159000D02*
X222500D01*
X222000Y158500D01*
G01X220000D02*
Y159500D01*
G01Y162000D02*
X222500D01*
X222000Y161500D01*
G01X220000D02*
Y162500D01*
G01Y164167D02*
X222500D01*
Y165208D01*
X222375Y165542D01*
X222208Y165750D01*
X221875Y165833D01*
X221542Y165750D01*
X221333Y165500D01*
X221208Y165208D01*
Y164167D01*
G01Y165208D02*
X220000Y165833D01*
G01Y168000D02*
X222500D01*
X222000Y167500D01*
G01X220000D02*
Y168500D01*
G01X222500Y171000D02*
X222417Y170667D01*
X222208Y170417D01*
X221958Y170250D01*
X221625Y170125D01*
X221250Y170083D01*
X220875Y170125D01*
X220542Y170250D01*
X220292Y170417D01*
X220083Y170667D01*
X220000Y171000D01*
X220083Y171333D01*
X220292Y171583D01*
X220542Y171750D01*
X220875Y171875D01*
X221250Y171917D01*
X221625Y171875D01*
X221958Y171750D01*
X222208Y171583D01*
X222417Y171333D01*
X222500Y171000D01*
G01X228333Y319000D02*
Y321500D01*
X227333D01*
X227000Y321375D01*
X226750Y321083D01*
X226667Y320750D01*
X226750Y320417D01*
X226958Y320167D01*
X227333Y320042D01*
X228333D01*
G01X223583Y321292D02*
X223833Y321417D01*
X224125Y321500D01*
X224458D01*
X224833Y321375D01*
X225125Y321167D01*
X225333Y320917D01*
X225500Y320500D01*
X225542Y320125D01*
X225458Y319750D01*
X225333Y319500D01*
X225083Y319250D01*
X224792Y319083D01*
X224500Y319000D01*
X224208D01*
X223917Y319083D01*
X223667Y319208D01*
X223458Y319375D01*
G01X221000Y319000D02*
Y321500D01*
X222542Y319708D01*
X220458D01*
G01X218500Y321500D02*
X218833Y321417D01*
X219083Y321208D01*
X219250Y320958D01*
X219375Y320625D01*
X219417Y320250D01*
X219375Y319875D01*
X219250Y319542D01*
X219083Y319292D01*
X218833Y319083D01*
X218500Y319000D01*
X218167Y319083D01*
X217917Y319292D01*
X217750Y319542D01*
X217625Y319875D01*
X217583Y320250D01*
X217625Y320625D01*
X217750Y320958D01*
X217917Y321208D01*
X218167Y321417D01*
X218500Y321500D01*
G01X228333Y312500D02*
Y315000D01*
X227333D01*
X227000Y314875D01*
X226750Y314583D01*
X226667Y314250D01*
X226750Y313917D01*
X226958Y313667D01*
X227333Y313542D01*
X228333D01*
G01X225333Y312500D02*
Y315000D01*
X224292D01*
X223958Y314875D01*
X223750Y314708D01*
X223667Y314375D01*
X223750Y314042D01*
X224000Y313833D01*
X224292Y313708D01*
X225333D01*
G01X224292D02*
X223667Y312500D01*
G01X222417Y313000D02*
X222167Y312708D01*
X221833Y312542D01*
X221458Y312500D01*
X221125Y312542D01*
X220792Y312750D01*
X220583Y313000D01*
X220542Y313250D01*
X220625Y313542D01*
X220917Y313750D01*
X221208Y313833D01*
X221583D01*
G01X221208D02*
X220958Y313958D01*
X220750Y314167D01*
X220667Y314417D01*
X220750Y314667D01*
X220958Y314875D01*
X221333Y315000D01*
X221708Y314958D01*
X222083Y314792D01*
G01X218500Y312500D02*
X218208Y312542D01*
X217875Y312667D01*
X217667Y312875D01*
X217583Y313167D01*
X217667Y313458D01*
X217917Y313708D01*
X218292Y313833D01*
X218708D01*
X218958Y313917D01*
X219167Y314125D01*
X219250Y314417D01*
X219125Y314708D01*
X218833Y314917D01*
X218500Y315000D01*
X218167Y314917D01*
X217875Y314708D01*
X217750Y314417D01*
X217833Y314125D01*
X218042Y313917D01*
X218292Y313833D01*
X218708D01*
X219083Y313708D01*
X219333Y313458D01*
X219417Y313167D01*
X219333Y312875D01*
X219125Y312667D01*
X218792Y312542D01*
X218500Y312500D01*
G01X229083Y72292D02*
X229333Y72417D01*
X229625Y72500D01*
X229958D01*
X230333Y72375D01*
X230625Y72167D01*
X230833Y71917D01*
X231000Y71500D01*
X231042Y71125D01*
X230958Y70750D01*
X230833Y70500D01*
X230583Y70250D01*
X230292Y70083D01*
X230000Y70000D01*
X229708D01*
X229417Y70083D01*
X229167Y70208D01*
X228958Y70375D01*
G01X227917Y70500D02*
X227667Y70208D01*
X227333Y70042D01*
X226958Y70000D01*
X226625Y70042D01*
X226292Y70250D01*
X226083Y70500D01*
X226042Y70750D01*
X226125Y71042D01*
X226417Y71250D01*
X226708Y71333D01*
X227083D01*
G01X226708D02*
X226458Y71458D01*
X226250Y71667D01*
X226167Y71917D01*
X226250Y72167D01*
X226458Y72375D01*
X226833Y72500D01*
X227208Y72458D01*
X227583Y72292D01*
G01X224792Y71042D02*
X224500Y71333D01*
X224250Y71500D01*
X223917Y71583D01*
X223625Y71500D01*
X223417Y71333D01*
X223250Y71083D01*
X223208Y70792D01*
X223250Y70542D01*
X223417Y70292D01*
X223667Y70083D01*
X223958Y70000D01*
X224292Y70083D01*
X224583Y70333D01*
X224750Y70708D01*
X224792Y71125D01*
X224708Y71667D01*
X224583Y71958D01*
X224375Y72250D01*
X224083Y72458D01*
X223792Y72500D01*
X223500Y72417D01*
X223292Y72208D01*
G01X224000Y145667D02*
X226500D01*
Y146708D01*
X226375Y147042D01*
X226208Y147250D01*
X225875Y147333D01*
X225542Y147250D01*
X225333Y147000D01*
X225208Y146708D01*
Y145667D01*
G01Y146708D02*
X224000Y147333D01*
G01Y149500D02*
X224042Y149792D01*
X224167Y150125D01*
X224375Y150333D01*
X224667Y150417D01*
X224958Y150333D01*
X225208Y150083D01*
X225333Y149708D01*
Y149292D01*
X225417Y149042D01*
X225625Y148833D01*
X225917Y148750D01*
X226208Y148875D01*
X226417Y149167D01*
X226500Y149500D01*
X226417Y149833D01*
X226208Y150125D01*
X225917Y150250D01*
X225625Y150167D01*
X225417Y149958D01*
X225333Y149708D01*
Y149292D01*
X225208Y148917D01*
X224958Y148667D01*
X224667Y148583D01*
X224375Y148667D01*
X224167Y148875D01*
X224042Y149208D01*
X224000Y149500D01*
G01X229083Y139792D02*
X229333Y139917D01*
X229625Y140000D01*
X229958D01*
X230333Y139875D01*
X230625Y139667D01*
X230833Y139417D01*
X231000Y139000D01*
X231042Y138625D01*
X230958Y138250D01*
X230833Y138000D01*
X230583Y137750D01*
X230292Y137583D01*
X230000Y137500D01*
X229708D01*
X229417Y137583D01*
X229167Y137708D01*
X228958Y137875D01*
G01X227917Y138000D02*
X227667Y137708D01*
X227333Y137542D01*
X226958Y137500D01*
X226625Y137542D01*
X226292Y137750D01*
X226083Y138000D01*
X226042Y138250D01*
X226125Y138542D01*
X226417Y138750D01*
X226708Y138833D01*
X227083D01*
G01X226708D02*
X226458Y138958D01*
X226250Y139167D01*
X226167Y139417D01*
X226250Y139667D01*
X226458Y139875D01*
X226833Y140000D01*
X227208Y139958D01*
X227583Y139792D01*
G01X224917Y137875D02*
X224667Y137667D01*
X224375Y137542D01*
X224000Y137500D01*
X223625Y137583D01*
X223333Y137750D01*
X223125Y138042D01*
X223083Y138375D01*
X223167Y138708D01*
X223375Y138917D01*
X223667Y139083D01*
X223958Y139125D01*
X224250Y139083D01*
X224625Y138917D01*
X224500Y140000D01*
X223375D01*
G01X223500Y155167D02*
X226000D01*
Y156208D01*
X225875Y156542D01*
X225708Y156750D01*
X225375Y156833D01*
X225042Y156750D01*
X224833Y156500D01*
X224708Y156208D01*
Y155167D01*
G01Y156208D02*
X223500Y156833D01*
G01Y158917D02*
X224042Y159000D01*
X224500Y159125D01*
X224917Y159292D01*
X225375Y159500D01*
X226000Y159833D01*
Y158167D01*
G01X223500Y164167D02*
X226000D01*
Y165208D01*
X225875Y165542D01*
X225708Y165750D01*
X225375Y165833D01*
X225042Y165750D01*
X224833Y165500D01*
X224708Y165208D01*
Y164167D01*
G01Y165208D02*
X223500Y165833D01*
G01X224542Y167208D02*
X224833Y167500D01*
X225000Y167750D01*
X225083Y168083D01*
X225000Y168375D01*
X224833Y168583D01*
X224583Y168750D01*
X224292Y168792D01*
X224042Y168750D01*
X223792Y168583D01*
X223583Y168333D01*
X223500Y168042D01*
X223583Y167708D01*
X223833Y167417D01*
X224208Y167250D01*
X224625Y167208D01*
X225167Y167292D01*
X225458Y167417D01*
X225750Y167625D01*
X225958Y167917D01*
X226000Y168208D01*
X225917Y168500D01*
X225708Y168708D01*
G01X229083Y248292D02*
X229333Y248417D01*
X229625Y248500D01*
X229958D01*
X230333Y248375D01*
X230625Y248167D01*
X230833Y247917D01*
X231000Y247500D01*
X231042Y247125D01*
X230958Y246750D01*
X230833Y246500D01*
X230583Y246250D01*
X230292Y246083D01*
X230000Y246000D01*
X229708D01*
X229417Y246083D01*
X229167Y246208D01*
X228958Y246375D01*
G01X227000Y246000D02*
Y248500D01*
X227500Y248000D01*
G01Y246000D02*
X226500D01*
G01X224792Y247042D02*
X224500Y247333D01*
X224250Y247500D01*
X223917Y247583D01*
X223625Y247500D01*
X223417Y247333D01*
X223250Y247083D01*
X223208Y246792D01*
X223250Y246542D01*
X223417Y246292D01*
X223667Y246083D01*
X223958Y246000D01*
X224292Y246083D01*
X224583Y246333D01*
X224750Y246708D01*
X224792Y247125D01*
X224708Y247667D01*
X224583Y247958D01*
X224375Y248250D01*
X224083Y248458D01*
X223792Y248500D01*
X223500Y248417D01*
X223292Y248208D01*
G01X226500Y298167D02*
X229000D01*
Y299167D01*
X228875Y299500D01*
X228583Y299750D01*
X228250Y299833D01*
X227917Y299750D01*
X227667Y299542D01*
X227542Y299167D01*
Y298167D01*
G01X226500Y301167D02*
X229000D01*
Y302208D01*
X228875Y302542D01*
X228708Y302750D01*
X228375Y302833D01*
X228042Y302750D01*
X227833Y302500D01*
X227708Y302208D01*
Y301167D01*
G01Y302208D02*
X226500Y302833D01*
G01X228583Y304208D02*
X228833Y304458D01*
X228958Y304750D01*
X229000Y305083D01*
X228917Y305500D01*
X228708Y305792D01*
X228458Y305875D01*
X228208Y305833D01*
X228000Y305667D01*
X227583Y304833D01*
X227292Y304458D01*
X226875Y304208D01*
X226500Y304125D01*
Y305875D01*
G01X227542Y307208D02*
X227833Y307500D01*
X228000Y307750D01*
X228083Y308083D01*
X228000Y308375D01*
X227833Y308583D01*
X227583Y308750D01*
X227292Y308792D01*
X227042Y308750D01*
X226792Y308583D01*
X226583Y308333D01*
X226500Y308042D01*
X226583Y307708D01*
X226833Y307417D01*
X227208Y307250D01*
X227625Y307208D01*
X228167Y307292D01*
X228458Y307417D01*
X228750Y307625D01*
X228958Y307917D01*
X229000Y308208D01*
X228917Y308500D01*
X228708Y308708D01*
G01X231000Y298167D02*
X233500D01*
Y299167D01*
X233375Y299500D01*
X233083Y299750D01*
X232750Y299833D01*
X232417Y299750D01*
X232167Y299542D01*
X232042Y299167D01*
Y298167D01*
G01X233292Y302917D02*
X233417Y302667D01*
X233500Y302375D01*
Y302042D01*
X233375Y301667D01*
X233167Y301375D01*
X232917Y301167D01*
X232500Y301000D01*
X232125Y300958D01*
X231750Y301042D01*
X231500Y301167D01*
X231250Y301417D01*
X231083Y301708D01*
X231000Y302000D01*
Y302292D01*
X231083Y302583D01*
X231208Y302833D01*
X231375Y303042D01*
G01X231000Y305500D02*
X233500D01*
X231708Y303958D01*
Y306042D01*
G01X231000Y308000D02*
X233500D01*
X233000Y307500D01*
G01X231000D02*
Y308500D01*
G01X254000Y77500D02*
Y75000D01*
G01X254958Y77500D02*
X253042D01*
G01X251833Y75000D02*
Y77500D01*
X250833D01*
X250500Y77375D01*
X250250Y77083D01*
X250167Y76750D01*
X250250Y76417D01*
X250458Y76167D01*
X250833Y76042D01*
X251833D01*
G01X248000Y75000D02*
X247708Y75042D01*
X247375Y75167D01*
X247167Y75375D01*
X247083Y75667D01*
X247167Y75958D01*
X247417Y76208D01*
X247792Y76333D01*
X248208D01*
X248458Y76417D01*
X248667Y76625D01*
X248750Y76917D01*
X248625Y77208D01*
X248333Y77417D01*
X248000Y77500D01*
X247667Y77417D01*
X247375Y77208D01*
X247250Y76917D01*
X247333Y76625D01*
X247542Y76417D01*
X247792Y76333D01*
X248208D01*
X248583Y76208D01*
X248833Y75958D01*
X248917Y75667D01*
X248833Y75375D01*
X248625Y75167D01*
X248292Y75042D01*
X248000Y75000D01*
G01X251333Y96000D02*
Y98500D01*
X250292D01*
X249958Y98375D01*
X249750Y98208D01*
X249667Y97875D01*
X249750Y97542D01*
X250000Y97333D01*
X250292Y97208D01*
X251333D01*
G01X250292D02*
X249667Y96000D01*
G01X248417Y96500D02*
X248167Y96208D01*
X247833Y96042D01*
X247458Y96000D01*
X247125Y96042D01*
X246792Y96250D01*
X246583Y96500D01*
X246542Y96750D01*
X246625Y97042D01*
X246917Y97250D01*
X247208Y97333D01*
X247583D01*
G01X247208D02*
X246958Y97458D01*
X246750Y97667D01*
X246667Y97917D01*
X246750Y98167D01*
X246958Y98375D01*
X247333Y98500D01*
X247708Y98458D01*
X248083Y98292D01*
G01X244583Y96000D02*
X244500Y96542D01*
X244375Y97000D01*
X244208Y97417D01*
X244000Y97875D01*
X243667Y98500D01*
X245333D01*
G01X251333Y88000D02*
Y90500D01*
X250292D01*
X249958Y90375D01*
X249750Y90208D01*
X249667Y89875D01*
X249750Y89542D01*
X250000Y89333D01*
X250292Y89208D01*
X251333D01*
G01X250292D02*
X249667Y88000D01*
G01X247000D02*
Y90500D01*
X248542Y88708D01*
X246458D01*
G01X245292Y90083D02*
X245042Y90333D01*
X244750Y90458D01*
X244417Y90500D01*
X244000Y90417D01*
X243708Y90208D01*
X243625Y89958D01*
X243667Y89708D01*
X243833Y89500D01*
X244667Y89083D01*
X245042Y88792D01*
X245292Y88375D01*
X245375Y88000D01*
X243625D01*
G01X248909Y143248D02*
Y145748D01*
X247868D01*
X247534Y145623D01*
X247326Y145456D01*
X247243Y145123D01*
X247326Y144790D01*
X247576Y144581D01*
X247868Y144456D01*
X248909D01*
G01X247868D02*
X247243Y143248D01*
G01X245993Y143623D02*
X245743Y143415D01*
X245451Y143290D01*
X245076Y143248D01*
X244701Y143331D01*
X244409Y143498D01*
X244201Y143790D01*
X244159Y144123D01*
X244243Y144456D01*
X244451Y144665D01*
X244743Y144831D01*
X245034Y144873D01*
X245326Y144831D01*
X245701Y144665D01*
X245576Y145748D01*
X244451D01*
G01X251333Y160000D02*
Y162500D01*
X250292D01*
X249958Y162375D01*
X249750Y162208D01*
X249667Y161875D01*
X249750Y161542D01*
X250000Y161333D01*
X250292Y161208D01*
X251333D01*
G01X250292D02*
X249667Y160000D01*
G01X248292Y162083D02*
X248042Y162333D01*
X247750Y162458D01*
X247417Y162500D01*
X247000Y162417D01*
X246708Y162208D01*
X246625Y161958D01*
X246667Y161708D01*
X246833Y161500D01*
X247667Y161083D01*
X248042Y160792D01*
X248292Y160375D01*
X248375Y160000D01*
X246625D01*
G01X244500D02*
Y162500D01*
X245000Y162000D01*
G01Y160000D02*
X244000D01*
G01X248909Y147248D02*
Y149748D01*
X247868D01*
X247534Y149623D01*
X247326Y149456D01*
X247243Y149123D01*
X247326Y148790D01*
X247576Y148581D01*
X247868Y148456D01*
X248909D01*
G01X247868D02*
X247243Y147248D01*
G01X245784Y147540D02*
X245493Y147331D01*
X245159Y147248D01*
X244826Y147331D01*
X244534Y147581D01*
X244326Y147956D01*
X244243Y148331D01*
Y148790D01*
X244326Y149165D01*
X244534Y149498D01*
X244784Y149665D01*
X245076Y149748D01*
X245409Y149665D01*
X245659Y149498D01*
X245826Y149248D01*
X245909Y148915D01*
X245826Y148623D01*
X245618Y148331D01*
X245368Y148165D01*
X245076Y148123D01*
X244743Y148206D01*
X244493Y148415D01*
X244243Y148790D01*
G01X259833Y171000D02*
Y173500D01*
X258792D01*
X258458Y173375D01*
X258250Y173208D01*
X258167Y172875D01*
X258250Y172542D01*
X258500Y172333D01*
X258792Y172208D01*
X259833D01*
G01X258792D02*
X258167Y171000D01*
G01X256792Y173083D02*
X256542Y173333D01*
X256250Y173458D01*
X255917Y173500D01*
X255500Y173417D01*
X255208Y173208D01*
X255125Y172958D01*
X255167Y172708D01*
X255333Y172500D01*
X256167Y172083D01*
X256542Y171792D01*
X256792Y171375D01*
X256875Y171000D01*
X255125D01*
G01X252500D02*
Y173500D01*
X254042Y171708D01*
X251958D01*
G01X249583Y166292D02*
X249833Y166417D01*
X250125Y166500D01*
X250458D01*
X250833Y166375D01*
X251125Y166167D01*
X251333Y165917D01*
X251500Y165500D01*
X251542Y165125D01*
X251458Y164750D01*
X251333Y164500D01*
X251083Y164250D01*
X250792Y164083D01*
X250500Y164000D01*
X250208D01*
X249917Y164083D01*
X249667Y164208D01*
X249458Y164375D01*
G01X248417Y164500D02*
X248167Y164208D01*
X247833Y164042D01*
X247458Y164000D01*
X247125Y164042D01*
X246792Y164250D01*
X246583Y164500D01*
X246542Y164750D01*
X246625Y165042D01*
X246917Y165250D01*
X247208Y165333D01*
X247583D01*
G01X247208D02*
X246958Y165458D01*
X246750Y165667D01*
X246667Y165917D01*
X246750Y166167D01*
X246958Y166375D01*
X247333Y166500D01*
X247708Y166458D01*
X248083Y166292D01*
G01X245208Y164292D02*
X244917Y164083D01*
X244583Y164000D01*
X244250Y164083D01*
X243958Y164333D01*
X243750Y164708D01*
X243667Y165083D01*
Y165542D01*
X243750Y165917D01*
X243958Y166250D01*
X244208Y166417D01*
X244500Y166500D01*
X244833Y166417D01*
X245083Y166250D01*
X245250Y166000D01*
X245333Y165667D01*
X245250Y165375D01*
X245042Y165083D01*
X244792Y164917D01*
X244500Y164875D01*
X244167Y164958D01*
X243917Y165167D01*
X243667Y165542D01*
G01X258083Y169292D02*
X258333Y169417D01*
X258625Y169500D01*
X258958D01*
X259333Y169375D01*
X259625Y169167D01*
X259833Y168917D01*
X260000Y168500D01*
X260042Y168125D01*
X259958Y167750D01*
X259833Y167500D01*
X259583Y167250D01*
X259292Y167083D01*
X259000Y167000D01*
X258708D01*
X258417Y167083D01*
X258167Y167208D01*
X257958Y167375D01*
G01X255500Y167000D02*
Y169500D01*
X257042Y167708D01*
X254958D01*
G01X253000Y167000D02*
Y169500D01*
X253500Y169000D01*
G01Y167000D02*
X252500D01*
G01X252583Y179792D02*
X252833Y179917D01*
X253125Y180000D01*
X253458D01*
X253833Y179875D01*
X254125Y179667D01*
X254333Y179417D01*
X254500Y179000D01*
X254542Y178625D01*
X254458Y178250D01*
X254333Y178000D01*
X254083Y177750D01*
X253792Y177583D01*
X253500Y177500D01*
X253208D01*
X252917Y177583D01*
X252667Y177708D01*
X252458Y177875D01*
G01X250500Y177500D02*
Y180000D01*
X251000Y179500D01*
G01Y177500D02*
X250000D01*
G01X247583D02*
X247500Y178042D01*
X247375Y178500D01*
X247208Y178917D01*
X247000Y179375D01*
X246667Y180000D01*
X248333D01*
G01X247000Y188000D02*
X244500D01*
G01X247000Y187042D02*
Y188958D01*
G01X244500Y190167D02*
X247000D01*
Y191167D01*
X246875Y191500D01*
X246583Y191750D01*
X246250Y191833D01*
X245917Y191750D01*
X245667Y191542D01*
X245542Y191167D01*
Y190167D01*
G01Y193208D02*
X245833Y193500D01*
X246000Y193750D01*
X246083Y194083D01*
X246000Y194375D01*
X245833Y194583D01*
X245583Y194750D01*
X245292Y194792D01*
X245042Y194750D01*
X244792Y194583D01*
X244583Y194333D01*
X244500Y194042D01*
X244583Y193708D01*
X244833Y193417D01*
X245208Y193250D01*
X245625Y193208D01*
X246167Y193292D01*
X246458Y193417D01*
X246750Y193625D01*
X246958Y193917D01*
X247000Y194208D01*
X246917Y194500D01*
X246708Y194708D01*
G01X264000Y77500D02*
Y75000D01*
G01X264958Y77500D02*
X263042D01*
G01X261833Y75000D02*
Y77500D01*
X260833D01*
X260500Y77375D01*
X260250Y77083D01*
X260167Y76750D01*
X260250Y76417D01*
X260458Y76167D01*
X260833Y76042D01*
X261833D01*
G01X258708Y75292D02*
X258417Y75083D01*
X258083Y75000D01*
X257750Y75083D01*
X257458Y75333D01*
X257250Y75708D01*
X257167Y76083D01*
Y76542D01*
X257250Y76917D01*
X257458Y77250D01*
X257708Y77417D01*
X258000Y77500D01*
X258333Y77417D01*
X258583Y77250D01*
X258750Y77000D01*
X258833Y76667D01*
X258750Y76375D01*
X258542Y76083D01*
X258292Y75917D01*
X258000Y75875D01*
X257667Y75958D01*
X257417Y76167D01*
X257167Y76542D01*
G01X275917Y150500D02*
Y148708D01*
X275750Y148333D01*
X275417Y148083D01*
X275000Y148000D01*
X274583Y148083D01*
X274250Y148333D01*
X274083Y148708D01*
Y150500D01*
G01X272917Y148500D02*
X272667Y148208D01*
X272333Y148042D01*
X271958Y148000D01*
X271625Y148042D01*
X271292Y148250D01*
X271083Y148500D01*
X271042Y148750D01*
X271125Y149042D01*
X271417Y149250D01*
X271708Y149333D01*
X272083D01*
G01X271708D02*
X271458Y149458D01*
X271250Y149667D01*
X271167Y149917D01*
X271250Y150167D01*
X271458Y150375D01*
X271833Y150500D01*
X272208Y150458D01*
X272583Y150292D01*
G01X266500Y188000D02*
X264000D01*
G01X266500Y187042D02*
Y188958D01*
G01X264000Y190167D02*
X266500D01*
Y191167D01*
X266375Y191500D01*
X266083Y191750D01*
X265750Y191833D01*
X265417Y191750D01*
X265167Y191542D01*
X265042Y191167D01*
Y190167D01*
G01X264000Y193917D02*
X264542Y194000D01*
X265000Y194125D01*
X265417Y194292D01*
X265875Y194500D01*
X266500Y194833D01*
Y193167D01*
G01X269833Y202000D02*
Y204500D01*
X268792D01*
X268458Y204375D01*
X268250Y204208D01*
X268167Y203875D01*
X268250Y203542D01*
X268500Y203333D01*
X268792Y203208D01*
X269833D01*
G01X268792D02*
X268167Y202000D01*
G01X266917Y202500D02*
X266667Y202208D01*
X266333Y202042D01*
X265958Y202000D01*
X265625Y202042D01*
X265292Y202250D01*
X265083Y202500D01*
X265042Y202750D01*
X265125Y203042D01*
X265417Y203250D01*
X265708Y203333D01*
X266083D01*
G01X265708D02*
X265458Y203458D01*
X265250Y203667D01*
X265167Y203917D01*
X265250Y204167D01*
X265458Y204375D01*
X265833Y204500D01*
X266208Y204458D01*
X266583Y204292D01*
G01X263917Y202500D02*
X263667Y202208D01*
X263333Y202042D01*
X262958Y202000D01*
X262625Y202042D01*
X262292Y202250D01*
X262083Y202500D01*
X262042Y202750D01*
X262125Y203042D01*
X262417Y203250D01*
X262708Y203333D01*
X263083D01*
G01X262708D02*
X262458Y203458D01*
X262250Y203667D01*
X262167Y203917D01*
X262250Y204167D01*
X262458Y204375D01*
X262833Y204500D01*
X263208Y204458D01*
X263583Y204292D01*
G01X269833Y198000D02*
Y200500D01*
X268792D01*
X268458Y200375D01*
X268250Y200208D01*
X268167Y199875D01*
X268250Y199542D01*
X268500Y199333D01*
X268792Y199208D01*
X269833D01*
G01X268792D02*
X268167Y198000D01*
G01X265500D02*
Y200500D01*
X267042Y198708D01*
X264958D01*
G01X263917Y198500D02*
X263667Y198208D01*
X263333Y198042D01*
X262958Y198000D01*
X262625Y198042D01*
X262292Y198250D01*
X262083Y198500D01*
X262042Y198750D01*
X262125Y199042D01*
X262417Y199250D01*
X262708Y199333D01*
X263083D01*
G01X262708D02*
X262458Y199458D01*
X262250Y199667D01*
X262167Y199917D01*
X262250Y200167D01*
X262458Y200375D01*
X262833Y200500D01*
X263208Y200458D01*
X263583Y200292D01*
G01X260000Y234167D02*
X262500D01*
Y235208D01*
X262375Y235542D01*
X262208Y235750D01*
X261875Y235833D01*
X261542Y235750D01*
X261333Y235500D01*
X261208Y235208D01*
Y234167D01*
G01Y235208D02*
X260000Y235833D01*
G01Y238000D02*
X262500D01*
X262000Y237500D01*
G01X260000D02*
Y238500D01*
G01Y241500D02*
X262500D01*
X260708Y239958D01*
Y242042D01*
G01X286333Y130000D02*
Y132500D01*
X285292D01*
X284958Y132375D01*
X284750Y132208D01*
X284667Y131875D01*
X284750Y131542D01*
X285000Y131333D01*
X285292Y131208D01*
X286333D01*
G01X285292D02*
X284667Y130000D01*
G01X282500D02*
Y132500D01*
X283000Y132000D01*
G01Y130000D02*
X282000D01*
G01X280417Y130375D02*
X280167Y130167D01*
X279875Y130042D01*
X279500Y130000D01*
X279125Y130083D01*
X278833Y130250D01*
X278625Y130542D01*
X278583Y130875D01*
X278667Y131208D01*
X278875Y131417D01*
X279167Y131583D01*
X279458Y131625D01*
X279750Y131583D01*
X280125Y131417D01*
X280000Y132500D01*
X278875D01*
G01X286333Y135000D02*
Y137500D01*
X285292D01*
X284958Y137375D01*
X284750Y137208D01*
X284667Y136875D01*
X284750Y136542D01*
X285000Y136333D01*
X285292Y136208D01*
X286333D01*
G01X285292D02*
X284667Y135000D01*
G01X282000D02*
Y137500D01*
X283542Y135708D01*
X281458D01*
G01X279500Y135000D02*
X279208Y135042D01*
X278875Y135167D01*
X278667Y135375D01*
X278583Y135667D01*
X278667Y135958D01*
X278917Y136208D01*
X279292Y136333D01*
X279708D01*
X279958Y136417D01*
X280167Y136625D01*
X280250Y136917D01*
X280125Y137208D01*
X279833Y137417D01*
X279500Y137500D01*
X279167Y137417D01*
X278875Y137208D01*
X278750Y136917D01*
X278833Y136625D01*
X279042Y136417D01*
X279292Y136333D01*
X279708D01*
X280083Y136208D01*
X280333Y135958D01*
X280417Y135667D01*
X280333Y135375D01*
X280125Y135167D01*
X279792Y135042D01*
X279500Y135000D01*
G01X287000Y159667D02*
X289500D01*
Y160708D01*
X289375Y161042D01*
X289208Y161250D01*
X288875Y161333D01*
X288542Y161250D01*
X288333Y161000D01*
X288208Y160708D01*
Y159667D01*
G01Y160708D02*
X287000Y161333D01*
G01X289083Y162708D02*
X289333Y162958D01*
X289458Y163250D01*
X289500Y163583D01*
X289417Y164000D01*
X289208Y164292D01*
X288958Y164375D01*
X288708Y164333D01*
X288500Y164167D01*
X288083Y163333D01*
X287792Y162958D01*
X287375Y162708D01*
X287000Y162625D01*
Y164375D01*
G01X287500Y165583D02*
X287208Y165833D01*
X287042Y166167D01*
X287000Y166542D01*
X287042Y166875D01*
X287250Y167208D01*
X287500Y167417D01*
X287750Y167458D01*
X288042Y167375D01*
X288250Y167083D01*
X288333Y166792D01*
Y166417D01*
G01Y166792D02*
X288458Y167042D01*
X288667Y167250D01*
X288917Y167333D01*
X289167Y167250D01*
X289375Y167042D01*
X289500Y166667D01*
X289458Y166292D01*
X289292Y165917D01*
G01X274000Y234167D02*
X276500D01*
Y235208D01*
X276375Y235542D01*
X276208Y235750D01*
X275875Y235833D01*
X275542Y235750D01*
X275333Y235500D01*
X275208Y235208D01*
Y234167D01*
G01Y235208D02*
X274000Y235833D01*
G01Y238500D02*
X276500D01*
X274708Y236958D01*
Y239042D01*
G01X274292Y240292D02*
X274083Y240583D01*
X274000Y240917D01*
X274083Y241250D01*
X274333Y241542D01*
X274708Y241750D01*
X275083Y241833D01*
X275542D01*
X275917Y241750D01*
X276250Y241542D01*
X276417Y241292D01*
X276500Y241000D01*
X276417Y240667D01*
X276250Y240417D01*
X276000Y240250D01*
X275667Y240167D01*
X275375Y240250D01*
X275083Y240458D01*
X274917Y240708D01*
X274875Y241000D01*
X274958Y241333D01*
X275167Y241583D01*
X275542Y241833D01*
G01X299833Y133625D02*
X299625Y133958D01*
X299500Y134333D01*
Y134667D01*
X299625Y135000D01*
X299833Y135250D01*
X300125Y135375D01*
X300417Y135292D01*
X300667Y135083D01*
X300833Y134708D01*
X300917Y134208D01*
X301083Y133917D01*
X301375Y133792D01*
X301667Y133875D01*
X301875Y134083D01*
X302000Y134375D01*
Y134667D01*
X301917Y134958D01*
X301708Y135208D01*
G01X299500Y136583D02*
X302000D01*
G01Y138167D02*
X300458Y136583D01*
G01X299500Y138417D02*
X301167Y137292D01*
G01X302000Y140500D02*
X299500D01*
G01X302000Y139542D02*
Y141458D01*
G01X299500Y143500D02*
X302000D01*
X301500Y143000D01*
G01X299500D02*
Y144000D01*
G54D16*
G01X-148956Y-251503D02*
Y-269003D01*
X-140222D01*
G01X-127089Y-257337D02*
Y-269003D01*
G01Y-252670D02*
X-127526Y-252378D01*
Y-251795D01*
X-127089Y-251503D01*
X-126652Y-251795D01*
Y-252378D01*
X-127089Y-252670D01*
G01X-112646Y-273378D02*
X-111117Y-274545D01*
X-109371Y-274836D01*
X-107843Y-274545D01*
X-106532Y-273087D01*
X-105659Y-271045D01*
Y-257337D01*
G01Y-259670D02*
X-106532Y-258503D01*
X-107843Y-257628D01*
X-109371Y-257337D01*
X-111117Y-257920D01*
X-112209Y-259086D01*
X-113083Y-261128D01*
X-113519Y-263170D01*
X-113301Y-264920D01*
X-112427Y-266962D01*
X-111117Y-268420D01*
X-109371Y-269003D01*
X-108061Y-268711D01*
X-106532Y-267545D01*
X-105659Y-266379D01*
G01X-95801Y-269003D02*
Y-251503D01*
G01Y-259961D02*
X-94709Y-258503D01*
X-93617Y-257628D01*
X-91871Y-257337D01*
X-90561Y-257628D01*
X-89032Y-258795D01*
X-88377Y-260545D01*
Y-269003D01*
G01X-74589Y-251503D02*
Y-269003D01*
G01X-77646Y-257337D02*
X-71532D01*
G01X-60801Y-269003D02*
Y-257337D01*
G01Y-260253D02*
X-59927Y-258795D01*
X-58617Y-257628D01*
X-56871Y-257337D01*
X-55343Y-257628D01*
X-54032Y-258795D01*
X-53377Y-260836D01*
Y-269003D01*
G01X-39589Y-257337D02*
Y-269003D01*
G01Y-252670D02*
X-40026Y-252378D01*
Y-251795D01*
X-39589Y-251503D01*
X-39152Y-251795D01*
Y-252378D01*
X-39589Y-252670D01*
G01X-25801Y-269003D02*
Y-257337D01*
G01Y-260253D02*
X-24927Y-258795D01*
X-23617Y-257628D01*
X-21871Y-257337D01*
X-20343Y-257628D01*
X-19032Y-258795D01*
X-18377Y-260836D01*
Y-269003D01*
G01X-7646Y-273378D02*
X-6117Y-274545D01*
X-4371Y-274836D01*
X-2843Y-274545D01*
X-1532Y-273087D01*
X-659Y-271045D01*
Y-257337D01*
G01Y-259670D02*
X-1532Y-258503D01*
X-2843Y-257628D01*
X-4371Y-257337D01*
X-6117Y-257920D01*
X-7209Y-259086D01*
X-8083Y-261128D01*
X-8519Y-263170D01*
X-8301Y-264920D01*
X-7427Y-266962D01*
X-6117Y-268420D01*
X-4371Y-269003D01*
X-3061Y-268711D01*
X-1532Y-267545D01*
X-659Y-266379D01*
G01X26044Y-269003D02*
Y-251503D01*
X31284D01*
X33031Y-252378D01*
X34341Y-254420D01*
X34778Y-256753D01*
X34341Y-259086D01*
X33249Y-260836D01*
X31284Y-261712D01*
X26044D01*
G01X42452Y-251503D02*
X47911Y-269003D01*
X53370Y-251503D01*
G01X65411D02*
Y-269003D01*
G01X60389Y-251503D02*
X70433D01*
G01X94734Y-269003D02*
Y-251503D01*
X100411Y-266086D01*
X106088Y-251503D01*
Y-269003D01*
G01X117911Y-269586D02*
X117474Y-269295D01*
Y-268711D01*
X117911Y-268420D01*
X118348Y-268711D01*
Y-269295D01*
X117911Y-269586D01*
G01X131263Y-254420D02*
X132573Y-252670D01*
X134101Y-251795D01*
X135848Y-251503D01*
X138031Y-252086D01*
X139559Y-253545D01*
X139996Y-255294D01*
X139778Y-257045D01*
X138904Y-258503D01*
X134538Y-261420D01*
X132573Y-263461D01*
X131263Y-266379D01*
X130826Y-269003D01*
X139996D01*
G01X164952D02*
X170411Y-251503D01*
X175870Y-269003D01*
G01X173904Y-262878D02*
X166917D01*
G01X191841Y-251503D02*
Y-269003D01*
G01Y-266379D02*
X190968Y-267837D01*
X189657Y-268711D01*
X188129Y-269003D01*
X186383Y-268420D01*
X185073Y-266962D01*
X184199Y-265212D01*
X183981Y-263170D01*
X184199Y-261128D01*
X185073Y-259378D01*
X186383Y-257920D01*
X188129Y-257337D01*
X189657Y-257628D01*
X190749Y-258212D01*
X191841Y-259378D01*
G01X209341Y-269003D02*
Y-257337D01*
G01Y-259378D02*
X208468Y-258212D01*
X207157Y-257628D01*
X205629Y-257337D01*
X204101Y-257920D01*
X202791Y-259086D01*
X201917Y-260836D01*
X201481Y-263170D01*
X201917Y-265503D01*
X202791Y-267253D01*
X204101Y-268420D01*
X205629Y-269003D01*
X207157Y-268711D01*
X208468Y-267837D01*
X209341Y-266670D01*
G01X218981Y-274836D02*
Y-257337D01*
G01Y-259961D02*
X220073Y-258503D01*
X221164Y-257628D01*
X222911Y-257337D01*
X224439Y-257628D01*
X225968Y-259086D01*
X226623Y-261128D01*
X226841Y-263170D01*
X226623Y-265212D01*
X225968Y-267253D01*
X224657Y-268420D01*
X222911Y-269003D01*
X221383Y-268711D01*
X219854Y-267837D01*
X218981Y-266670D01*
G01X240411Y-251503D02*
Y-269003D01*
G01X237354Y-257337D02*
X243468D01*
G01X257911Y-269003D02*
X256601Y-268711D01*
X255291Y-267545D01*
X254417Y-265503D01*
X253981Y-263170D01*
X254417Y-260836D01*
X255291Y-258795D01*
X256601Y-257628D01*
X257911Y-257337D01*
X259221Y-257628D01*
X260531Y-258795D01*
X261404Y-260836D01*
X261623Y-263170D01*
X261404Y-265503D01*
X260531Y-267545D01*
X259221Y-268711D01*
X257911Y-269003D01*
G01X272354D02*
Y-257337D01*
G01Y-259670D02*
X273446Y-258503D01*
X274538Y-257628D01*
X276066Y-257337D01*
X277157Y-257628D01*
X278468Y-258503D01*
G01X315214Y-252962D02*
X313904Y-252086D01*
X312376Y-251503D01*
X310629D01*
X308664Y-252378D01*
X307136Y-253836D01*
X306044Y-255587D01*
X305171Y-258503D01*
X304952Y-261128D01*
X305389Y-263753D01*
X306044Y-265503D01*
X307354Y-267253D01*
X308883Y-268420D01*
X310411Y-269003D01*
X311939D01*
X313468Y-268420D01*
X314778Y-267545D01*
X315870Y-266379D01*
G01X331841Y-269003D02*
Y-257337D01*
G01Y-259378D02*
X330968Y-258212D01*
X329657Y-257628D01*
X328129Y-257337D01*
X326601Y-257920D01*
X325291Y-259086D01*
X324417Y-260836D01*
X323981Y-263170D01*
X324417Y-265503D01*
X325291Y-267253D01*
X326601Y-268420D01*
X328129Y-269003D01*
X329657Y-268711D01*
X330968Y-267837D01*
X331841Y-266670D01*
G01X342354Y-269003D02*
Y-257337D01*
G01Y-259670D02*
X343446Y-258503D01*
X344538Y-257628D01*
X346066Y-257337D01*
X347157Y-257628D01*
X348468Y-258503D01*
G01X366841Y-251503D02*
Y-269003D01*
G01Y-266379D02*
X365968Y-267837D01*
X364657Y-268711D01*
X363129Y-269003D01*
X361383Y-268420D01*
X360073Y-266962D01*
X359199Y-265212D01*
X358981Y-263170D01*
X359199Y-261128D01*
X360073Y-259378D01*
X361383Y-257920D01*
X363129Y-257337D01*
X364657Y-257628D01*
X365749Y-258212D01*
X366841Y-259378D01*
G01X68484Y-224003D02*
Y-206503D01*
X74161Y-221086D01*
X79838Y-206503D01*
Y-224003D01*
G01X91661D02*
X90351Y-223711D01*
X89041Y-222545D01*
X88167Y-220503D01*
X87731Y-218170D01*
X88167Y-215836D01*
X89041Y-213795D01*
X90351Y-212628D01*
X91661Y-212337D01*
X92971Y-212628D01*
X94281Y-213795D01*
X95154Y-215836D01*
X95373Y-218170D01*
X95154Y-220503D01*
X94281Y-222545D01*
X92971Y-223711D01*
X91661Y-224003D01*
G01X113091Y-206503D02*
Y-224003D01*
G01Y-221379D02*
X112218Y-222837D01*
X110907Y-223711D01*
X109379Y-224003D01*
X107633Y-223420D01*
X106323Y-221962D01*
X105449Y-220212D01*
X105231Y-218170D01*
X105449Y-216128D01*
X106323Y-214378D01*
X107633Y-212920D01*
X109379Y-212337D01*
X110907Y-212628D01*
X111999Y-213212D01*
X113091Y-214378D01*
G01X123386Y-216128D02*
X130373D01*
X129718Y-214086D01*
X128626Y-212920D01*
X127098Y-212337D01*
X125569Y-212628D01*
X124259Y-213503D01*
X123386Y-215545D01*
X122949Y-217295D01*
Y-219045D01*
X123386Y-220795D01*
X124478Y-222545D01*
X125788Y-223711D01*
X127316Y-224003D01*
X128844Y-223420D01*
X130373Y-221670D01*
G01X144161Y-224003D02*
Y-206503D01*
G01X424761Y-269003D02*
Y-251503D01*
X422141Y-255003D01*
G01Y-269003D02*
X427381D01*
G01X437458Y-266379D02*
X438767Y-267837D01*
X440296Y-268711D01*
X442261Y-269003D01*
X444226Y-268420D01*
X445754Y-267253D01*
X446846Y-265212D01*
X447064Y-262878D01*
X446628Y-260545D01*
X445536Y-259086D01*
X444007Y-257920D01*
X442479Y-257628D01*
X440951Y-257920D01*
X438986Y-259086D01*
X439641Y-251503D01*
X445536D01*
G01X459324Y-269003D02*
X459761Y-265212D01*
X460416Y-262003D01*
X461289Y-259086D01*
X462381Y-255878D01*
X464128Y-251503D01*
X455394D01*
G01X472458Y-266379D02*
X473767Y-267837D01*
X475296Y-268711D01*
X477261Y-269003D01*
X479226Y-268420D01*
X480754Y-267253D01*
X481846Y-265212D01*
X482064Y-262878D01*
X481628Y-260545D01*
X480536Y-259086D01*
X479007Y-257920D01*
X477479Y-257628D01*
X475951Y-257920D01*
X473986Y-259086D01*
X474641Y-251503D01*
X480536D01*
G01X494761D02*
X493014Y-252086D01*
X491704Y-253545D01*
X490831Y-255294D01*
X490176Y-257628D01*
X489958Y-260253D01*
X490176Y-262878D01*
X490831Y-265212D01*
X491704Y-266962D01*
X493014Y-268420D01*
X494761Y-269003D01*
X496507Y-268420D01*
X497818Y-266962D01*
X498691Y-265212D01*
X499346Y-262878D01*
X499564Y-260253D01*
X499346Y-257628D01*
X498691Y-255294D01*
X497818Y-253545D01*
X496507Y-252086D01*
X494761Y-251503D01*
G01X411644Y-224003D02*
Y-206503D01*
X416884D01*
X418631Y-207378D01*
X419941Y-209420D01*
X420378Y-211753D01*
X419941Y-214086D01*
X418849Y-215836D01*
X416884Y-216712D01*
X411644D01*
G01X438314Y-207962D02*
X437004Y-207086D01*
X435476Y-206503D01*
X433729D01*
X431764Y-207378D01*
X430236Y-208836D01*
X429144Y-210587D01*
X428271Y-213503D01*
X428052Y-216128D01*
X428489Y-218753D01*
X429144Y-220503D01*
X430454Y-222253D01*
X431983Y-223420D01*
X433511Y-224003D01*
X435039D01*
X436568Y-223420D01*
X437878Y-222545D01*
X438970Y-221379D01*
G01X452757Y-214670D02*
X453631Y-213795D01*
X454286Y-212337D01*
X454723Y-210294D01*
X454286Y-208545D01*
X453413Y-207378D01*
X451884Y-206503D01*
X445989D01*
Y-224003D01*
X453194D01*
X454723Y-222837D01*
X455596Y-221086D01*
X456033Y-219045D01*
X455596Y-217003D01*
X454286Y-215253D01*
X452757Y-214670D01*
X445989D01*
G01X461961Y-229836D02*
X475061D01*
G01X480989Y-224003D02*
Y-206503D01*
X491033Y-224003D01*
Y-206503D01*
G01X503511Y-224003D02*
X501764Y-223711D01*
X500236Y-222545D01*
X498926Y-220795D01*
X498052Y-218753D01*
X497616Y-216420D01*
Y-214086D01*
X498052Y-211753D01*
X498926Y-209711D01*
X500236Y-207962D01*
X501764Y-206795D01*
X503511Y-206503D01*
X505257Y-206795D01*
X506786Y-207962D01*
X508096Y-209711D01*
X508970Y-211753D01*
X509406Y-214086D01*
Y-216420D01*
X508970Y-218753D01*
X508096Y-220795D01*
X506786Y-222545D01*
X505257Y-223711D01*
X503511Y-224003D01*
G01X554352Y-206503D02*
X559811Y-224003D01*
X565270Y-206503D01*
G01X581678Y-224003D02*
X572944D01*
Y-206503D01*
X581678D01*
G01X578184Y-214961D02*
X572944D01*
G01X590444Y-224003D02*
Y-206503D01*
X595903D01*
X597649Y-207378D01*
X598741Y-208545D01*
X599178Y-210878D01*
X598741Y-213212D01*
X597431Y-214670D01*
X595903Y-215545D01*
X590444D01*
G01X595903D02*
X599178Y-224003D01*
G01X612311Y-224586D02*
X611874Y-224295D01*
Y-223711D01*
X612311Y-223420D01*
X612748Y-223711D01*
Y-224295D01*
X612311Y-224586D01*
G01X586061Y-269003D02*
Y-251503D01*
X583441Y-255003D01*
G01Y-269003D02*
X588681D01*
G01X760515Y-259670D02*
X759641Y-258795D01*
X758986Y-257337D01*
X758549Y-255294D01*
X758986Y-253545D01*
X759859Y-252378D01*
X761388Y-251503D01*
X767283D01*
Y-269003D01*
X760078D01*
X758549Y-267837D01*
X757676Y-266086D01*
X757239Y-264045D01*
X757676Y-262003D01*
X758986Y-260253D01*
X760515Y-259670D01*
X767283D01*
G01X749346Y-266670D02*
X747599Y-268128D01*
X745634Y-269003D01*
X743888D01*
X742141Y-268128D01*
X740831Y-266670D01*
X740176Y-264628D01*
X740613Y-262587D01*
X741704Y-260836D01*
X743669Y-259670D01*
X746289Y-259086D01*
X747818Y-257920D01*
X748473Y-255878D01*
X748036Y-253836D01*
X746944Y-252378D01*
X745416Y-251503D01*
X743888D01*
X742359Y-252086D01*
X741049Y-253545D01*
G01X729881Y-251503D02*
X724641D01*
G01X727261D02*
Y-269003D01*
G01X729881D02*
X724641D01*
G01X714128Y-251503D02*
Y-269003D01*
X705394D01*
G01X697064D02*
Y-251503D01*
G01X688768D02*
X697064Y-262295D01*
G01X687458Y-269003D02*
X693353Y-257337D01*
G01X687894Y-206503D02*
Y-224003D01*
X696628D01*
G01X713691D02*
Y-212337D01*
G01Y-214378D02*
X712818Y-213212D01*
X711507Y-212628D01*
X709979Y-212337D01*
X708451Y-212920D01*
X707141Y-214086D01*
X706267Y-215836D01*
X705831Y-218170D01*
X706267Y-220503D01*
X707141Y-222253D01*
X708451Y-223420D01*
X709979Y-224003D01*
X711507Y-223711D01*
X712818Y-222837D01*
X713691Y-221670D01*
G01X722676Y-229253D02*
X723986Y-229836D01*
X725733Y-229253D01*
X726824Y-228087D01*
X727698Y-226628D01*
X729007Y-221962D01*
X731846Y-212337D01*
G01X724859D02*
X729007Y-221962D01*
G01X741486Y-216128D02*
X748473D01*
X747818Y-214086D01*
X746726Y-212920D01*
X745198Y-212337D01*
X743669Y-212628D01*
X742359Y-213503D01*
X741486Y-215545D01*
X741049Y-217295D01*
Y-219045D01*
X741486Y-220795D01*
X742578Y-222545D01*
X743888Y-223711D01*
X745416Y-224003D01*
X746944Y-223420D01*
X748473Y-221670D01*
G01X759204Y-224003D02*
Y-212337D01*
G01Y-214670D02*
X760296Y-213503D01*
X761388Y-212628D01*
X762916Y-212337D01*
X764007Y-212628D01*
X765318Y-213503D01*
G01X830008Y-224003D02*
Y-206503D01*
X834374D01*
X836121Y-207378D01*
X837431Y-208545D01*
X838523Y-210294D01*
X839396Y-212337D01*
X839614Y-215253D01*
X839396Y-218170D01*
X838523Y-220212D01*
X837431Y-221962D01*
X836121Y-223128D01*
X834374Y-224003D01*
X830008D01*
G01X849036Y-216128D02*
X856023D01*
X855368Y-214086D01*
X854276Y-212920D01*
X852748Y-212337D01*
X851219Y-212628D01*
X849909Y-213503D01*
X849036Y-215545D01*
X848599Y-217295D01*
Y-219045D01*
X849036Y-220795D01*
X850128Y-222545D01*
X851438Y-223711D01*
X852966Y-224003D01*
X854494Y-223420D01*
X856023Y-221670D01*
G01X866536Y-221962D02*
X867628Y-223128D01*
X869156Y-224003D01*
X870466D01*
X871776Y-223420D01*
X872649Y-222545D01*
X873086Y-221379D01*
X872868Y-219628D01*
X871994Y-218753D01*
X868064Y-217003D01*
X867191Y-214961D01*
X867628Y-213503D01*
X868501Y-212628D01*
X869811Y-212337D01*
X871121Y-212628D01*
X872431Y-213503D01*
G01X887311Y-212337D02*
Y-224003D01*
G01Y-207670D02*
X886874Y-207378D01*
Y-206795D01*
X887311Y-206503D01*
X887748Y-206795D01*
Y-207378D01*
X887311Y-207670D01*
G01X901754Y-228378D02*
X903283Y-229545D01*
X905029Y-229836D01*
X906557Y-229545D01*
X907868Y-228087D01*
X908741Y-226045D01*
Y-212337D01*
G01Y-214670D02*
X907868Y-213503D01*
X906557Y-212628D01*
X905029Y-212337D01*
X903283Y-212920D01*
X902191Y-214086D01*
X901317Y-216128D01*
X900881Y-218170D01*
X901099Y-219920D01*
X901973Y-221962D01*
X903283Y-223420D01*
X905029Y-224003D01*
X906339Y-223711D01*
X907868Y-222545D01*
X908741Y-221379D01*
G01X918599Y-224003D02*
Y-212337D01*
G01Y-215253D02*
X919473Y-213795D01*
X920783Y-212628D01*
X922529Y-212337D01*
X924057Y-212628D01*
X925368Y-213795D01*
X926023Y-215836D01*
Y-224003D01*
G01X936536Y-216128D02*
X943523D01*
X942868Y-214086D01*
X941776Y-212920D01*
X940248Y-212337D01*
X938719Y-212628D01*
X937409Y-213503D01*
X936536Y-215545D01*
X936099Y-217295D01*
Y-219045D01*
X936536Y-220795D01*
X937628Y-222545D01*
X938938Y-223711D01*
X940466Y-224003D01*
X941994Y-223420D01*
X943523Y-221670D01*
G01X954254Y-224003D02*
Y-212337D01*
G01Y-214670D02*
X955346Y-213503D01*
X956438Y-212628D01*
X957966Y-212337D01*
X959057Y-212628D01*
X960368Y-213503D01*
G01X874194Y-265503D02*
X875286Y-267253D01*
X876596Y-268420D01*
X878124Y-269003D01*
X879871Y-268420D01*
X881181Y-267253D01*
X882491Y-265503D01*
X882928Y-263170D01*
Y-251503D01*
G01X896061Y-269003D02*
X894314Y-268711D01*
X892786Y-267545D01*
X891476Y-265795D01*
X890602Y-263753D01*
X890166Y-261420D01*
Y-259086D01*
X890602Y-256753D01*
X891476Y-254711D01*
X892786Y-252962D01*
X894314Y-251795D01*
X896061Y-251503D01*
X897807Y-251795D01*
X899336Y-252962D01*
X900646Y-254711D01*
X901520Y-256753D01*
X901956Y-259086D01*
Y-261420D01*
X901520Y-263753D01*
X900646Y-265795D01*
X899336Y-267545D01*
X897807Y-268711D01*
X896061Y-269003D01*
G01X913561D02*
Y-261128D01*
X909194Y-251503D01*
G01X917928D02*
X913561Y-261128D01*
G01X1001011Y-269003D02*
Y-251503D01*
X998391Y-255003D01*
G01Y-269003D02*
X1003631D01*
G01X1014363Y-254420D02*
X1015673Y-252670D01*
X1017201Y-251795D01*
X1018948Y-251503D01*
X1021131Y-252086D01*
X1022659Y-253545D01*
X1023096Y-255294D01*
X1022878Y-257045D01*
X1022004Y-258503D01*
X1017638Y-261420D01*
X1015673Y-263461D01*
X1014363Y-266379D01*
X1013926Y-269003D01*
X1023096D01*
G01X1032081Y-269586D02*
X1039941Y-251503D01*
G01X1048708Y-265503D02*
X1050017Y-267545D01*
X1051764Y-268711D01*
X1053729Y-269003D01*
X1055476Y-268711D01*
X1057223Y-267253D01*
X1058314Y-265503D01*
X1058533Y-263753D01*
X1058096Y-261712D01*
X1056568Y-260253D01*
X1055039Y-259670D01*
X1053074D01*
G01X1055039D02*
X1056349Y-258795D01*
X1057441Y-257337D01*
X1057878Y-255587D01*
X1057441Y-253836D01*
X1056349Y-252378D01*
X1054384Y-251503D01*
X1052419Y-251795D01*
X1050454Y-252962D01*
G01X1071011Y-251503D02*
X1069264Y-252086D01*
X1067954Y-253545D01*
X1067081Y-255294D01*
X1066426Y-257628D01*
X1066208Y-260253D01*
X1066426Y-262878D01*
X1067081Y-265212D01*
X1067954Y-266962D01*
X1069264Y-268420D01*
X1071011Y-269003D01*
X1072757Y-268420D01*
X1074068Y-266962D01*
X1074941Y-265212D01*
X1075596Y-262878D01*
X1075814Y-260253D01*
X1075596Y-257628D01*
X1074941Y-255294D01*
X1074068Y-253545D01*
X1072757Y-252086D01*
X1071011Y-251503D01*
G01X1084581Y-269586D02*
X1092441Y-251503D01*
G01X1101863Y-254420D02*
X1103173Y-252670D01*
X1104701Y-251795D01*
X1106448Y-251503D01*
X1108631Y-252086D01*
X1110159Y-253545D01*
X1110596Y-255294D01*
X1110378Y-257045D01*
X1109504Y-258503D01*
X1105138Y-261420D01*
X1103173Y-263461D01*
X1101863Y-266379D01*
X1101426Y-269003D01*
X1110596D01*
G01X1123511Y-251503D02*
X1121764Y-252086D01*
X1120454Y-253545D01*
X1119581Y-255294D01*
X1118926Y-257628D01*
X1118708Y-260253D01*
X1118926Y-262878D01*
X1119581Y-265212D01*
X1120454Y-266962D01*
X1121764Y-268420D01*
X1123511Y-269003D01*
X1125257Y-268420D01*
X1126568Y-266962D01*
X1127441Y-265212D01*
X1128096Y-262878D01*
X1128314Y-260253D01*
X1128096Y-257628D01*
X1127441Y-255294D01*
X1126568Y-253545D01*
X1125257Y-252086D01*
X1123511Y-251503D01*
G01X1141011Y-269003D02*
Y-251503D01*
X1138391Y-255003D01*
G01Y-269003D02*
X1143631D01*
G01X1154363Y-261712D02*
X1155891Y-259670D01*
X1157201Y-258503D01*
X1158948Y-257920D01*
X1160476Y-258503D01*
X1161568Y-259670D01*
X1162441Y-261420D01*
X1162659Y-263461D01*
X1162441Y-265212D01*
X1161568Y-266962D01*
X1160257Y-268420D01*
X1158729Y-269003D01*
X1156983Y-268420D01*
X1155454Y-266670D01*
X1154581Y-264045D01*
X1154363Y-261128D01*
X1154799Y-257337D01*
X1155454Y-255294D01*
X1156546Y-253253D01*
X1158074Y-251795D01*
X1159603Y-251503D01*
X1161131Y-252086D01*
X1162223Y-253545D01*
G01X1048708Y-224003D02*
Y-206503D01*
X1053074D01*
X1054821Y-207378D01*
X1056131Y-208545D01*
X1057223Y-210294D01*
X1058096Y-212337D01*
X1058314Y-215253D01*
X1058096Y-218170D01*
X1057223Y-220212D01*
X1056131Y-221962D01*
X1054821Y-223128D01*
X1053074Y-224003D01*
X1048708D01*
G01X1074941D02*
Y-212337D01*
G01Y-214378D02*
X1074068Y-213212D01*
X1072757Y-212628D01*
X1071229Y-212337D01*
X1069701Y-212920D01*
X1068391Y-214086D01*
X1067517Y-215836D01*
X1067081Y-218170D01*
X1067517Y-220503D01*
X1068391Y-222253D01*
X1069701Y-223420D01*
X1071229Y-224003D01*
X1072757Y-223711D01*
X1074068Y-222837D01*
X1074941Y-221670D01*
G01X1088511Y-206503D02*
Y-224003D01*
G01X1085454Y-212337D02*
X1091568D01*
G01X1102736Y-216128D02*
X1109723D01*
X1109068Y-214086D01*
X1107976Y-212920D01*
X1106448Y-212337D01*
X1104919Y-212628D01*
X1103609Y-213503D01*
X1102736Y-215545D01*
X1102299Y-217295D01*
Y-219045D01*
X1102736Y-220795D01*
X1103828Y-222545D01*
X1105138Y-223711D01*
X1106666Y-224003D01*
X1108194Y-223420D01*
X1109723Y-221670D01*
G01X101000Y278800D02*
X97000D01*
Y286200D01*
G01Y278800D02*
X93000D01*
Y286200D01*
G01X98000Y297700D02*
X102000D01*
Y290300D01*
G01X98500Y307700D02*
X102500D01*
Y300300D01*
G01X94500Y307700D02*
X98500D01*
Y300300D01*
G01X102500Y307700D02*
X106500D01*
Y300300D01*
G01X90500Y307700D02*
X94500D01*
Y300300D01*
G01X102200Y319000D02*
Y315000D01*
X94800D01*
G01X102200Y323000D02*
Y319000D01*
X94800D01*
G01X262167Y358500D02*
Y353500D01*
X258833D01*
G01X254900Y356833D02*
Y353500D01*
G01Y358167D02*
X255067Y358250D01*
Y358417D01*
X254900Y358500D01*
X254733Y358417D01*
Y358250D01*
X254900Y358167D01*
G01X250467Y352250D02*
X249883Y351917D01*
X249217Y351833D01*
X248633Y351917D01*
X248133Y352333D01*
X247800Y352917D01*
Y356833D01*
G01Y356167D02*
X248133Y356500D01*
X248633Y356750D01*
X249217Y356833D01*
X249883Y356667D01*
X250300Y356333D01*
X250633Y355750D01*
X250800Y355167D01*
X250717Y354667D01*
X250383Y354083D01*
X249883Y353667D01*
X249217Y353500D01*
X248717Y353583D01*
X248133Y353917D01*
X247800Y354250D01*
G01X245117Y353500D02*
Y358500D01*
G01Y356083D02*
X244700Y356500D01*
X244283Y356750D01*
X243617Y356833D01*
X243117Y356750D01*
X242533Y356417D01*
X242283Y355917D01*
Y353500D01*
G01X238100Y358500D02*
Y353500D01*
G01X239267Y356833D02*
X236933D01*
G01X233917Y353500D02*
Y356833D01*
G01Y356000D02*
X233583Y356417D01*
X233083Y356750D01*
X232417Y356833D01*
X231833Y356750D01*
X231333Y356417D01*
X231083Y355833D01*
Y353500D01*
G01X226900Y356833D02*
Y353500D01*
G01Y358167D02*
X227067Y358250D01*
Y358417D01*
X226900Y358500D01*
X226733Y358417D01*
Y358250D01*
X226900Y358167D01*
G01X222717Y353500D02*
Y356833D01*
G01Y356000D02*
X222383Y356417D01*
X221883Y356750D01*
X221217Y356833D01*
X220633Y356750D01*
X220133Y356417D01*
X219883Y355833D01*
Y353500D01*
G01X216867Y352250D02*
X216283Y351917D01*
X215617Y351833D01*
X215033Y351917D01*
X214533Y352333D01*
X214200Y352917D01*
Y356833D01*
G01Y356167D02*
X214533Y356500D01*
X215033Y356750D01*
X215617Y356833D01*
X216283Y356667D01*
X216700Y356333D01*
X217033Y355750D01*
X217200Y355167D01*
X217117Y354667D01*
X216783Y354083D01*
X216283Y353667D01*
X215617Y353500D01*
X215117Y353583D01*
X214533Y353917D01*
X214200Y354250D01*
G01X206167Y353500D02*
Y358500D01*
X204167D01*
X203500Y358250D01*
X203000Y357667D01*
X202833Y357000D01*
X203000Y356333D01*
X203417Y355833D01*
X204167Y355583D01*
X206167D01*
G01X200983Y358500D02*
X198900Y353500D01*
X196817Y358500D01*
G01X193300D02*
Y353500D01*
G01X195217Y358500D02*
X191383D01*
G01X184267Y353500D02*
Y358500D01*
X182100Y354333D01*
X179933Y358500D01*
Y353500D01*
G01X176500Y353333D02*
X176667Y353417D01*
Y353583D01*
X176500Y353667D01*
X176333Y353583D01*
Y353417D01*
X176500Y353333D01*
G01X172483Y357667D02*
X171983Y358167D01*
X171400Y358417D01*
X170733Y358500D01*
X169900Y358333D01*
X169317Y357917D01*
X169150Y357417D01*
X169233Y356917D01*
X169567Y356500D01*
X171233Y355667D01*
X171983Y355083D01*
X172483Y354250D01*
X172650Y353500D01*
X169150D01*
G01X161783D02*
X159700Y358500D01*
X157617Y353500D01*
G01X158367Y355250D02*
X161033D01*
G01X152600Y358500D02*
Y353500D01*
G01Y354250D02*
X152933Y353833D01*
X153433Y353583D01*
X154017Y353500D01*
X154683Y353667D01*
X155183Y354083D01*
X155517Y354583D01*
X155600Y355167D01*
X155517Y355750D01*
X155183Y356250D01*
X154683Y356667D01*
X154017Y356833D01*
X153433Y356750D01*
X153017Y356583D01*
X152600Y356250D01*
G01X147000Y353500D02*
Y356833D01*
G01Y356250D02*
X147333Y356583D01*
X147833Y356750D01*
X148417Y356833D01*
X149000Y356667D01*
X149500Y356333D01*
X149833Y355833D01*
X150000Y355167D01*
X149833Y354500D01*
X149500Y354000D01*
X149000Y353667D01*
X148417Y353500D01*
X147833Y353583D01*
X147333Y353833D01*
X147000Y354167D01*
G01X144400Y351833D02*
Y356833D01*
G01Y356083D02*
X143983Y356500D01*
X143567Y356750D01*
X142900Y356833D01*
X142317Y356750D01*
X141733Y356333D01*
X141483Y355750D01*
X141400Y355167D01*
X141483Y354583D01*
X141733Y354000D01*
X142233Y353667D01*
X142900Y353500D01*
X143483Y353583D01*
X144067Y353833D01*
X144400Y354167D01*
G01X137300Y358500D02*
Y353500D01*
G01X138467Y356833D02*
X136133D01*
G01X131700Y353500D02*
X132200Y353583D01*
X132700Y353917D01*
X133033Y354500D01*
X133200Y355167D01*
X133033Y355833D01*
X132700Y356417D01*
X132200Y356750D01*
X131700Y356833D01*
X131200Y356750D01*
X130700Y356417D01*
X130367Y355833D01*
X130283Y355167D01*
X130367Y354500D01*
X130700Y353917D01*
X131200Y353583D01*
X131700Y353500D01*
G01X127267D02*
Y356833D01*
G01Y356167D02*
X126850Y356500D01*
X126433Y356750D01*
X125850Y356833D01*
X125433Y356750D01*
X124933Y356500D01*
G01X113067Y358083D02*
X113567Y358333D01*
X114150Y358500D01*
X114817D01*
X115567Y358250D01*
X116150Y357833D01*
X116567Y357333D01*
X116900Y356500D01*
X116983Y355750D01*
X116817Y355000D01*
X116567Y354500D01*
X116067Y354000D01*
X115483Y353667D01*
X114900Y353500D01*
X114317D01*
X113733Y353667D01*
X113233Y353917D01*
X112817Y354250D01*
G01X107800Y353500D02*
Y356833D01*
G01Y356250D02*
X108133Y356583D01*
X108633Y356750D01*
X109217Y356833D01*
X109800Y356667D01*
X110300Y356333D01*
X110633Y355833D01*
X110800Y355167D01*
X110633Y354500D01*
X110300Y354000D01*
X109800Y353667D01*
X109217Y353500D01*
X108633Y353583D01*
X108133Y353833D01*
X107800Y354167D01*
G01X104867Y353500D02*
Y356833D01*
G01Y356167D02*
X104450Y356500D01*
X104033Y356750D01*
X103450Y356833D01*
X103033Y356750D01*
X102533Y356500D01*
G01X96600Y358500D02*
Y353500D01*
G01Y354250D02*
X96933Y353833D01*
X97433Y353583D01*
X98017Y353500D01*
X98683Y353667D01*
X99183Y354083D01*
X99517Y354583D01*
X99600Y355167D01*
X99517Y355750D01*
X99183Y356250D01*
X98683Y356667D01*
X98017Y356833D01*
X97433Y356750D01*
X97017Y356583D01*
X96600Y356250D01*
G01X112000Y278800D02*
X108000D01*
Y286200D01*
G01X116000Y278800D02*
X112000D01*
Y286200D01*
G01X117800Y291000D02*
Y295000D01*
X125200D01*
G01X117000Y313700D02*
X121000D01*
Y306300D01*
G01X113000Y313700D02*
X117000D01*
Y306300D01*
G01X119500Y335800D02*
X115500D01*
Y343200D01*
G01X123500Y335800D02*
X119500D01*
Y343200D01*
G01X107000D02*
X111000D01*
Y335800D01*
G01X111500Y343200D02*
X115500D01*
Y335800D01*
G01X170311Y296300D02*
X166311D01*
Y303700D01*
G01X174311Y296300D02*
X170311D01*
Y303700D01*
G01X178311Y296300D02*
X174311D01*
Y303700D01*
G01X259333Y340167D02*
X259000Y340417D01*
X258750Y340833D01*
X258583Y341417D01*
X258750Y341917D01*
X259083Y342250D01*
X259667Y342500D01*
X261917D01*
Y337500D01*
X259167D01*
X258583Y337833D01*
X258250Y338333D01*
X258083Y338917D01*
X258250Y339500D01*
X258750Y340000D01*
X259333Y340167D01*
X261917D01*
G01X253400Y337500D02*
Y342500D01*
X256483Y338917D01*
X252317D01*
G01X248800Y337500D02*
X248217Y337583D01*
X247550Y337833D01*
X247133Y338250D01*
X246967Y338833D01*
X247133Y339417D01*
X247633Y339917D01*
X248383Y340167D01*
X249217D01*
X249717Y340333D01*
X250133Y340750D01*
X250300Y341333D01*
X250050Y341917D01*
X249467Y342333D01*
X248800Y342500D01*
X248133Y342333D01*
X247550Y341917D01*
X247300Y341333D01*
X247467Y340750D01*
X247883Y340333D01*
X248383Y340167D01*
X249217D01*
X249967Y339917D01*
X250467Y339417D01*
X250633Y338833D01*
X250467Y338250D01*
X250050Y337833D01*
X249383Y337583D01*
X248800Y337500D01*
G01X243200Y337333D02*
X243367Y337417D01*
Y337583D01*
X243200Y337667D01*
X243033Y337583D01*
Y337417D01*
X243200Y337333D01*
G01X237600Y342500D02*
X238267Y342333D01*
X238767Y341917D01*
X239100Y341417D01*
X239350Y340750D01*
X239433Y340000D01*
X239350Y339250D01*
X239100Y338583D01*
X238767Y338083D01*
X238267Y337667D01*
X237600Y337500D01*
X236933Y337667D01*
X236433Y338083D01*
X236100Y338583D01*
X235850Y339250D01*
X235767Y340000D01*
X235850Y340750D01*
X236100Y341417D01*
X236433Y341917D01*
X236933Y342333D01*
X237600Y342500D01*
G01X232000D02*
X232667Y342333D01*
X233167Y341917D01*
X233500Y341417D01*
X233750Y340750D01*
X233833Y340000D01*
X233750Y339250D01*
X233500Y338583D01*
X233167Y338083D01*
X232667Y337667D01*
X232000Y337500D01*
X231333Y337667D01*
X230833Y338083D01*
X230500Y338583D01*
X230250Y339250D01*
X230167Y340000D01*
X230250Y340750D01*
X230500Y341417D01*
X230833Y341917D01*
X231333Y342333D01*
X232000Y342500D01*
G01X226400Y337500D02*
X227067Y337583D01*
X227650Y337917D01*
X228150Y338417D01*
X228483Y339000D01*
X228650Y339667D01*
Y340333D01*
X228483Y341000D01*
X228150Y341583D01*
X227650Y342083D01*
X227067Y342417D01*
X226400Y342500D01*
X225733Y342417D01*
X225150Y342083D01*
X224650Y341583D01*
X224317Y341000D01*
X224150Y340333D01*
Y339667D01*
X224317Y339000D01*
X224650Y338417D01*
X225150Y337917D01*
X225733Y337583D01*
X226400Y337500D01*
G01X225733Y338833D02*
X224733Y337500D01*
G01X220800Y342500D02*
X221467Y342333D01*
X221967Y341917D01*
X222300Y341417D01*
X222550Y340750D01*
X222633Y340000D01*
X222550Y339250D01*
X222300Y338583D01*
X221967Y338083D01*
X221467Y337667D01*
X220800Y337500D01*
X220133Y337667D01*
X219633Y338083D01*
X219300Y338583D01*
X219050Y339250D01*
X218967Y340000D01*
X219050Y340750D01*
X219300Y341417D01*
X219633Y341917D01*
X220133Y342333D01*
X220800Y342500D01*
G01X215367Y337500D02*
X215200Y338583D01*
X214950Y339500D01*
X214617Y340333D01*
X214200Y341250D01*
X213533Y342500D01*
X216867D01*
G01X209600Y337333D02*
X209767Y337417D01*
Y337583D01*
X209600Y337667D01*
X209433Y337583D01*
Y337417D01*
X209600Y337333D01*
G01X204000Y342500D02*
X204667Y342333D01*
X205167Y341917D01*
X205500Y341417D01*
X205750Y340750D01*
X205833Y340000D01*
X205750Y339250D01*
X205500Y338583D01*
X205167Y338083D01*
X204667Y337667D01*
X204000Y337500D01*
X203333Y337667D01*
X202833Y338083D01*
X202500Y338583D01*
X202250Y339250D01*
X202167Y340000D01*
X202250Y340750D01*
X202500Y341417D01*
X202833Y341917D01*
X203333Y342333D01*
X204000Y342500D01*
G01X198400D02*
X199067Y342333D01*
X199567Y341917D01*
X199900Y341417D01*
X200150Y340750D01*
X200233Y340000D01*
X200150Y339250D01*
X199900Y338583D01*
X199567Y338083D01*
X199067Y337667D01*
X198400Y337500D01*
X197733Y337667D01*
X197233Y338083D01*
X196900Y338583D01*
X196650Y339250D01*
X196567Y340000D01*
X196650Y340750D01*
X196900Y341417D01*
X197233Y341917D01*
X197733Y342333D01*
X198400Y342500D01*
G01X192800Y337500D02*
Y342500D01*
X193800Y341500D01*
G01Y337500D02*
X191800D01*
G01X187200D02*
Y342500D01*
X188200Y341500D01*
G01Y337500D02*
X186200D01*
G01X261667Y330000D02*
Y335000D01*
X259500Y330833D01*
X257333Y335000D01*
Y330000D01*
G01X255983D02*
X253900Y335000D01*
X251817Y330000D01*
G01X252567Y331750D02*
X255233D01*
G01X250133Y330000D02*
Y335000D01*
X248467D01*
X247800Y334750D01*
X247300Y334417D01*
X246883Y333917D01*
X246550Y333333D01*
X246467Y332500D01*
X246550Y331667D01*
X246883Y331083D01*
X247300Y330583D01*
X247800Y330250D01*
X248467Y330000D01*
X250133D01*
G01X241033D02*
X244367D01*
Y335000D01*
X241033D01*
G01X242367Y332583D02*
X244367D01*
G01X232500Y335000D02*
X230500D01*
G01X231500D02*
Y330000D01*
G01X232500D02*
X230500D01*
G01X227817D02*
Y335000D01*
X223983Y330000D01*
Y335000D01*
G01X214700D02*
Y330000D01*
G01X216617Y335000D02*
X212783D01*
G01X211183Y330000D02*
X209100Y335000D01*
X207017Y330000D01*
G01X207767Y331750D02*
X210433D01*
G01X204500Y335000D02*
X202500D01*
G01X203500D02*
Y330000D01*
G01X204500D02*
X202500D01*
G01X200400Y335000D02*
X199233Y330000D01*
X197900Y335000D01*
X196567Y330000D01*
X195400Y335000D01*
G01X194383Y330000D02*
X192300Y335000D01*
X190217Y330000D01*
G01X190967Y331750D02*
X193633D01*
G01X188617Y330000D02*
Y335000D01*
X184783Y330000D01*
Y335000D01*
G01X203800Y307500D02*
Y311500D01*
X211200D01*
G01X201811Y298800D02*
X197811D01*
Y306200D01*
G01X199011Y319000D02*
Y315000D01*
X191611D01*
G01X216311Y309700D02*
X220311D01*
Y302300D01*
G01X235311Y147300D02*
X231311D01*
Y154700D01*
G01Y162200D02*
X235311D01*
Y154800D01*
G01X227311Y154700D02*
X231311D01*
Y147300D01*
G01Y154800D02*
X227311D01*
Y162200D01*
G01X235311Y162300D02*
X231311D01*
Y169700D01*
G01X227311D02*
X231311D01*
Y162300D01*
G01X261000Y345500D02*
Y350500D01*
X262000Y349500D01*
G01Y345500D02*
X260000D01*
G01X257233Y346250D02*
X256733Y345833D01*
X256150Y345583D01*
X255400Y345500D01*
X254650Y345667D01*
X254067Y346000D01*
X253650Y346583D01*
X253567Y347250D01*
X253733Y347917D01*
X254150Y348333D01*
X254733Y348667D01*
X255317Y348750D01*
X255900Y348667D01*
X256650Y348333D01*
X256400Y350500D01*
X254150D01*
G01X249967Y345500D02*
X249800Y346583D01*
X249550Y347500D01*
X249217Y348333D01*
X248800Y349250D01*
X248133Y350500D01*
X251467D01*
G01X246033Y346250D02*
X245533Y345833D01*
X244950Y345583D01*
X244200Y345500D01*
X243450Y345667D01*
X242867Y346000D01*
X242450Y346583D01*
X242367Y347250D01*
X242533Y347917D01*
X242950Y348333D01*
X243533Y348667D01*
X244117Y348750D01*
X244700Y348667D01*
X245450Y348333D01*
X245200Y350500D01*
X242950D01*
G01X238600D02*
X239267Y350333D01*
X239767Y349917D01*
X240100Y349417D01*
X240350Y348750D01*
X240433Y348000D01*
X240350Y347250D01*
X240100Y346583D01*
X239767Y346083D01*
X239267Y345667D01*
X238600Y345500D01*
X237933Y345667D01*
X237433Y346083D01*
X237100Y346583D01*
X236850Y347250D01*
X236767Y348000D01*
X236850Y348750D01*
X237100Y349417D01*
X237433Y349917D01*
X237933Y350333D01*
X238600Y350500D01*
G01X234083Y347167D02*
X231917D01*
G01X227400Y345500D02*
Y350500D01*
X228400Y349500D01*
G01Y345500D02*
X226400D01*
G01X260200Y98500D02*
Y94500D01*
X252800D01*
G01Y86500D02*
Y90500D01*
X260200D01*
G01X260700Y162500D02*
Y158500D01*
X253300D01*
G01X243300Y154500D02*
Y158500D01*
X250700D01*
G01X243300Y150500D02*
Y154500D01*
X250700D01*
G01X252800Y195000D02*
Y199000D01*
X260200D01*
G01Y207000D02*
Y203000D01*
X252800D01*
G01X276700Y133500D02*
Y129500D01*
X269300D01*
G01X276700Y137500D02*
Y133500D01*
X269300D01*
G01X266500Y159300D02*
X262500D01*
Y166700D01*
G01X268500Y152300D02*
X278500D01*
G01X268500Y165700D02*
Y152300D01*
G01X278500Y165700D02*
X268500D01*
G01Y234800D02*
X264500D01*
Y242200D01*
G01X272500Y234800D02*
X268500D01*
Y242200D01*
G01X280500Y166700D02*
X284500D01*
Y159300D01*
G01X278500Y152300D02*
Y165700D01*
G01X319094Y191969D02*
Y175236D01*
G03X321063Y173268I1969J1D01*
G01X326181D01*
G02X328149Y171299I0J-1968D01*
G01Y45985D01*
G02X326181Y44016I-1968J-1D01*
G01X321063D01*
G03X319094Y42048I0J-1969D01*
G01Y25315D01*
G03X321063Y23347I1969J1D01*
G01X349409D01*
Y12692D01*
X343114D01*
Y4792D01*
X325414D01*
Y12692D01*
X318514D01*
Y23542D01*
X301214D01*
Y43842D01*
X305664D01*
Y173442D01*
X301214D01*
Y193742D01*
X318514D01*
Y204592D01*
X325414D01*
Y212492D01*
X343114D01*
Y204592D01*
X349409D01*
Y193937D01*
X321063D01*
G03X319094Y191969I0J-1969D01*
G01X338081Y117542D02*
X338414Y117009D01*
X338614Y116409D01*
Y115875D01*
X338414Y115342D01*
X338081Y114942D01*
X337614Y114742D01*
X337147Y114875D01*
X336747Y115209D01*
X336481Y115809D01*
X336347Y116609D01*
X336081Y117075D01*
X335614Y117275D01*
X335147Y117142D01*
X334814Y116809D01*
X334614Y116342D01*
Y115875D01*
X334747Y115409D01*
X335081Y115009D01*
G01X338614Y111542D02*
X334614D01*
G01X335947Y106942D02*
X338614D01*
G01X334881D02*
X334814Y107075D01*
X334681D01*
X334614Y106942D01*
X334681Y106809D01*
X334814D01*
X334881Y106942D01*
G01X334614Y102342D02*
X338614D01*
G01X335947Y103275D02*
Y101409D01*
G54D17*
G01X146311Y314300D02*
Y315400D01*
G01Y311600D02*
Y312700D01*
G01X211000Y318000D02*
Y322000D01*
G01X207811Y314800D02*
Y315900D01*
G01Y312100D02*
Y313200D01*
M02*
